FILE_TYPE = MACRO_DRAWING;
SET COLOR_WIRE YELLOW;
SET COLOR_PROP ORANGE;
SET COLOR_DOT WHITE;
SET COLOR_ARC YELLOW;
SET COLOR_BODY GREEN;
SET COLOR_NOTE PURPLE;
SET PROP_DISPLAY VALUE;
SET PAGE_NUMBER P419;
FORCEADD OFFPAGE..1
(-8075 950);
FORCEPROP 2 LAST $XR0 182 
J 0
(-8327 950);
DISPLAY 0.638298 (-8327 950);
PAINT MONO (-8327 950);
FORCEPROP 2 LAST CDS_LIB standard
J 0
(-8075 950);
DISPLAY INVISIBLE (-8075 950);
FORCEPROP 1 LAST OFFPAGE TRUE
J 0
(-7750 825);
DISPLAY 0.872340 (-7750 825);
DISPLAY INVISIBLE (-7750 825);
FORCEPROP 1 LAST COMMENT_BODY TRUE
J 0
(-7950 850);
DISPLAY 0.872340 (-7950 850);
PAINT GREEN (-7950 850);
DISPLAY INVISIBLE (-7950 850);
FORCEPROP 2 LAST PATH I1
J 0
(-8350 1000);
DISPLAY 0.680851 (-8350 1000);
DISPLAY INVISIBLE (-8350 1000);
FORCEADD Q_RES..2
(-8975 5900);
FORCEPROP 1 LAST LOCATION R1069
J 0
(-8930 6025);
DISPLAY 0.787234 (-8930 6025);
FORCEPROP 0 LAST $SEC 1
J 0
(-8925 6075);
DISPLAY 0.680851 (-8925 6075);
PAINT MONO (-8925 6075);
DISPLAY INVISIBLE (-8925 6075);
FORCEPROP 0 LAST CDS_SEC 1
J 0
(-8925 6075);
DISPLAY 0.680851 (-8925 6075);
DISPLAY INVISIBLE (-8925 6075);
FORCEPROP 1 LASTPIN (-8975 6000) $PN 1
J 0
(-8970 5962);
DISPLAY 0.787234 (-8970 5962);
PAINT MONO (-8970 5962);
FORCEPROP 1 LASTPIN (-8975 5800) $PN 2
J 0
(-8970 5810);
DISPLAY 0.787234 (-8970 5810);
PAINT MONO (-8970 5810);
FORCEPROP 1 LAST TOLERANCE 5%
J 0
(-8930 5925);
DISPLAY 0.787234 (-8930 5925);
FORCEPROP 1 LAST VALUE 4.7K
J 0
(-8930 5975);
DISPLAY 0.787234 (-8930 5975);
FORCEPROP 1 LAST PACK_TYPE 0201LF
J 0
(-8925 5750);
DISPLAY 0.787234 (-8925 5750);
FORCEPROP 1 LAST MATERIAL EMPTY
J 0
(-8935 5825);
DISPLAY 0.787234 (-8935 5825);
FORCEPROP 1 LAST WATTAGE 1/20W
J 0
(-8935 5875);
DISPLAY 0.787234 (-8935 5875);
FORCEPROP 2 LAST CDS_LIB pure_quanta
J 0
(-8975 5900);
DISPLAY INVISIBLE (-8975 5900);
FORCEPROP 1 LAST PATH I10
J 0
(-8925 6075);
DISPLAY 0.978723 (-8925 6075);
PAINT WHITE (-8925 6075);
DISPLAY INVISIBLE (-8925 6075);
FORCEPROP 1 LAST PART_NUMBER CS24701JE04
J 0
(-8935 5775);
DISPLAY 0.978723 (-8935 5775);
DISPLAY INVISIBLE (-8935 5775);
FORCEADD UNIVERSAL_GND..1
R 1
(-1975 2200);
FORCEPROP 3 LASTPIN (-2025 2200) SIG_NAME GND\g
J 0
(-2015 2210);
DISPLAY 0.659574 (-2015 2210);
PAINT MONO (-2015 2210);
DISPLAY INVISIBLE (-2015 2210);
FORCEPROP 2 LAST CDS_LIB pure_quanta_power
J 0
(-1975 2200);
DISPLAY INVISIBLE (-1975 2200);
FORCEPROP 1 LAST HDL_POWER GND
R 1
J 1
(-1900 2225);
DISPLAY 0.872340 (-1900 2225);
PAINT GREEN (-1900 2225);
DISPLAY INVISIBLE (-1900 2225);
FORCEPROP 1 LAST PATH I100
R 1
J 0
(-1975 2275);
DISPLAY 0.872340 (-1975 2275);
PAINT AQUA (-1975 2275);
DISPLAY INVISIBLE (-1975 2275);
FORCEADD OFFPAGE..1
R 2
(-2425 2600);
FORCEPROP 2 LAST $XR0 299 
J 0
(-2239 2600);
DISPLAY 0.638298 (-2239 2600);
PAINT MONO (-2239 2600);
FORCEPROP 2 LAST CDS_LIB standard
J 0
(-2425 2600);
DISPLAY INVISIBLE (-2425 2600);
FORCEPROP 1 LAST OFFPAGE TRUE
J 2
(-2750 2475);
DISPLAY 0.872340 (-2750 2475);
DISPLAY INVISIBLE (-2750 2475);
FORCEPROP 1 LAST COMMENT_BODY TRUE
J 2
(-2550 2500);
DISPLAY 0.872340 (-2550 2500);
PAINT GREEN (-2550 2500);
DISPLAY INVISIBLE (-2550 2500);
FORCEPROP 2 LAST PATH I101
J 0
(-2250 2675);
DISPLAY 0.680851 (-2250 2675);
DISPLAY INVISIBLE (-2250 2675);
FORCEADD Q_RES..2
(-9000 3350);
FORCEPROP 1 LAST LOCATION R1064
J 0
(-8955 3475);
DISPLAY 0.978723 (-8955 3475);
PAINT WHITE (-8955 3475);
FORCEPROP 0 LAST $SEC 1
J 0
(-8950 3525);
DISPLAY 0.680851 (-8950 3525);
PAINT MONO (-8950 3525);
DISPLAY INVISIBLE (-8950 3525);
FORCEPROP 0 LAST CDS_SEC 1
J 0
(-8950 3525);
DISPLAY 0.680851 (-8950 3525);
DISPLAY INVISIBLE (-8950 3525);
FORCEPROP 1 LASTPIN (-9000 3450) $PN 1
J 0
(-8995 3412);
DISPLAY 0.787234 (-8995 3412);
PAINT MONO (-8995 3412);
FORCEPROP 1 LASTPIN (-9000 3250) $PN 2
J 0
(-8995 3260);
DISPLAY 0.787234 (-8995 3260);
PAINT MONO (-8995 3260);
FORCEPROP 1 LAST PACK_TYPE 0201LF
J 0
(-8960 3175);
DISPLAY 0.978723 (-8960 3175);
FORCEPROP 1 LAST MATERIAL CHIP
J 0
(-8960 3275);
DISPLAY 0.978723 (-8960 3275);
FORCEPROP 1 LAST WATTAGE 1/20W
J 0
(-8960 3325);
DISPLAY 0.978723 (-8960 3325);
FORCEPROP 1 LAST TOLERANCE 1%
J 0
(-8955 3375);
DISPLAY 0.978723 (-8955 3375);
FORCEPROP 1 LAST VALUE 200
J 0
(-8955 3425);
DISPLAY 0.978723 (-8955 3425);
FORCEPROP 2 LAST CDS_LIB pure_quanta
J 0
(-9000 3350);
DISPLAY INVISIBLE (-9000 3350);
FORCEPROP 1 LAST PATH I102
J 0
(-8950 3525);
DISPLAY 0.978723 (-8950 3525);
PAINT WHITE (-8950 3525);
DISPLAY INVISIBLE (-8950 3525);
FORCEPROP 1 LAST PART_NUMBER CS12001FE12
J 0
(-8960 3225);
DISPLAY 0.978723 (-8960 3225);
DISPLAY INVISIBLE (-8960 3225);
FORCEADD OFFPAGE..5
(-2600 900);
FORCEPROP 2 LAST $XR0 299 
J 0
(-2855 900);
DISPLAY 0.638298 (-2855 900);
PAINT MONO (-2855 900);
FORCEPROP 2 LAST CDS_LIB standard
J 0
(-2600 900);
DISPLAY INVISIBLE (-2600 900);
FORCEPROP 1 LAST OFFPAGE TRUE
J 0
(-2275 775);
DISPLAY 0.872340 (-2275 775);
PAINT GREEN (-2275 775);
DISPLAY INVISIBLE (-2275 775);
FORCEPROP 1 LAST COMMENT_BODY TRUE
J 0
(-2500 825);
DISPLAY 0.872340 (-2500 825);
PAINT GREEN (-2500 825);
DISPLAY INVISIBLE (-2500 825);
FORCEPROP 2 LAST PATH I103
J 0
(-2550 975);
DISPLAY 0.680851 (-2550 975);
DISPLAY INVISIBLE (-2550 975);
FORCEADD OFFPAGE..5
(-2600 950);
FORCEPROP 2 LAST $XR0 299 
J 0
(-2855 950);
DISPLAY 0.638298 (-2855 950);
PAINT MONO (-2855 950);
FORCEPROP 2 LAST CDS_LIB standard
J 0
(-2600 950);
DISPLAY INVISIBLE (-2600 950);
FORCEPROP 1 LAST OFFPAGE TRUE
J 0
(-2275 825);
DISPLAY 0.872340 (-2275 825);
PAINT GREEN (-2275 825);
DISPLAY INVISIBLE (-2275 825);
FORCEPROP 1 LAST COMMENT_BODY TRUE
J 0
(-2500 875);
DISPLAY 0.872340 (-2500 875);
PAINT GREEN (-2500 875);
DISPLAY INVISIBLE (-2500 875);
FORCEPROP 2 LAST PATH I105
J 0
(-2550 1025);
DISPLAY 0.680851 (-2550 1025);
DISPLAY INVISIBLE (-2550 1025);
FORCEADD OFFPAGE..5
(-2600 1000);
FORCEPROP 2 LAST $XR0 299 
J 0
(-2855 1000);
DISPLAY 0.638298 (-2855 1000);
PAINT MONO (-2855 1000);
FORCEPROP 2 LAST CDS_LIB standard
J 0
(-2600 1000);
DISPLAY INVISIBLE (-2600 1000);
FORCEPROP 1 LAST OFFPAGE TRUE
J 0
(-2275 875);
DISPLAY 0.872340 (-2275 875);
PAINT GREEN (-2275 875);
DISPLAY INVISIBLE (-2275 875);
FORCEPROP 1 LAST COMMENT_BODY TRUE
J 0
(-2500 925);
DISPLAY 0.872340 (-2500 925);
PAINT GREEN (-2500 925);
DISPLAY INVISIBLE (-2500 925);
FORCEPROP 2 LAST PATH I106
J 0
(-2550 1075);
DISPLAY 0.680851 (-2550 1075);
DISPLAY INVISIBLE (-2550 1075);
FORCEADD OFFPAGE..5
(-2600 1050);
FORCEPROP 2 LAST $XR0 299 
J 0
(-2855 1050);
DISPLAY 0.638298 (-2855 1050);
PAINT MONO (-2855 1050);
FORCEPROP 2 LAST CDS_LIB standard
J 2
(-2600 1050);
DISPLAY INVISIBLE (-2600 1050);
FORCEPROP 1 LAST OFFPAGE TRUE
J 0
(-2275 925);
DISPLAY 0.872340 (-2275 925);
PAINT GREEN (-2275 925);
DISPLAY INVISIBLE (-2275 925);
FORCEPROP 1 LAST COMMENT_BODY TRUE
J 0
(-2500 975);
DISPLAY 0.872340 (-2500 975);
PAINT GREEN (-2500 975);
DISPLAY INVISIBLE (-2500 975);
FORCEPROP 2 LAST PATH I107
J 0
(-2550 1125);
DISPLAY 0.680851 (-2550 1125);
DISPLAY INVISIBLE (-2550 1125);
FORCEADD Q_RES..2
(-8350 5900);
FORCEPROP 1 LAST LOCATION R1073
J 0
(-8305 6025);
DISPLAY 0.787234 (-8305 6025);
FORCEPROP 0 LAST $SEC 1
J 0
(-8300 6075);
DISPLAY 0.680851 (-8300 6075);
PAINT MONO (-8300 6075);
DISPLAY INVISIBLE (-8300 6075);
FORCEPROP 0 LAST CDS_SEC 1
J 0
(-8300 6075);
DISPLAY 0.680851 (-8300 6075);
DISPLAY INVISIBLE (-8300 6075);
FORCEPROP 1 LASTPIN (-8350 6000) $PN 1
J 0
(-8345 5962);
DISPLAY 0.787234 (-8345 5962);
PAINT MONO (-8345 5962);
FORCEPROP 1 LASTPIN (-8350 5800) $PN 2
J 0
(-8345 5810);
DISPLAY 0.787234 (-8345 5810);
PAINT MONO (-8345 5810);
FORCEPROP 1 LAST MATERIAL EMPTY
J 0
(-8310 5825);
DISPLAY 0.787234 (-8310 5825);
FORCEPROP 1 LAST PACK_TYPE 0201LF
J 0
(-8300 5750);
DISPLAY 0.787234 (-8300 5750);
FORCEPROP 1 LAST WATTAGE 1/20W
J 0
(-8310 5875);
DISPLAY 0.787234 (-8310 5875);
FORCEPROP 1 LAST TOLERANCE 5%
J 0
(-8305 5925);
DISPLAY 0.787234 (-8305 5925);
FORCEPROP 1 LAST VALUE 4.7K
J 0
(-8305 5975);
DISPLAY 0.787234 (-8305 5975);
FORCEPROP 2 LAST CDS_LIB pure_quanta
J 0
(-8350 5900);
DISPLAY INVISIBLE (-8350 5900);
FORCEPROP 1 LAST PATH I11
J 0
(-8300 6075);
DISPLAY 0.978723 (-8300 6075);
PAINT WHITE (-8300 6075);
DISPLAY INVISIBLE (-8300 6075);
FORCEPROP 1 LAST PART_NUMBER CS24701JE04
J 0
(-8310 5775);
DISPLAY 0.978723 (-8310 5775);
DISPLAY INVISIBLE (-8310 5775);
FORCEADD Q_RES..2
(-1450 1300);
FORCEPROP 1 LAST LOCATION R1476
J 0
(-1405 1425);
DISPLAY 0.978723 (-1405 1425);
FORCEPROP 0 LAST $SEC 1
J 0
(-1400 1475);
DISPLAY 0.680851 (-1400 1475);
PAINT MONO (-1400 1475);
DISPLAY INVISIBLE (-1400 1475);
FORCEPROP 0 LAST CDS_SEC 1
J 0
(-1400 1475);
DISPLAY 0.680851 (-1400 1475);
DISPLAY INVISIBLE (-1400 1475);
FORCEPROP 1 LASTPIN (-1450 1400) $PN 1
J 0
(-1445 1362);
DISPLAY 0.787234 (-1445 1362);
PAINT MONO (-1445 1362);
FORCEPROP 1 LASTPIN (-1450 1200) $PN 2
J 0
(-1445 1210);
DISPLAY 0.787234 (-1445 1210);
PAINT MONO (-1445 1210);
FORCEPROP 1 LAST PACK_TYPE 0201LF
J 0
(-1400 1150);
DISPLAY 0.787234 (-1400 1150);
FORCEPROP 1 LAST MATERIAL EMPTY
J 0
(-1410 1225);
DISPLAY 0.787234 (-1410 1225);
PAINT RED (-1410 1225);
FORCEPROP 1 LAST WATTAGE 1/20W
J 0
(-1410 1275);
DISPLAY 0.787234 (-1410 1275);
FORCEPROP 1 LAST TOLERANCE 5%
J 0
(-1405 1325);
DISPLAY 0.787234 (-1405 1325);
FORCEPROP 1 LAST VALUE 4.7K
J 0
(-1405 1375);
DISPLAY 0.787234 (-1405 1375);
FORCEPROP 2 LAST CDS_LIB pure_quanta
J 0
(-1450 1300);
DISPLAY INVISIBLE (-1450 1300);
FORCEPROP 1 LAST PATH I116
J 0
(-1400 1475);
DISPLAY 0.978723 (-1400 1475);
PAINT WHITE (-1400 1475);
DISPLAY INVISIBLE (-1400 1475);
FORCEPROP 1 LAST PART_NUMBER CS24701JE04
J 0
(-1410 1175);
DISPLAY 0.978723 (-1410 1175);
DISPLAY INVISIBLE (-1410 1175);
FORCEADD Q_RES..2
(-1175 1300);
FORCEPROP 1 LAST LOCATION R1477
J 0
(-1130 1425);
DISPLAY 0.978723 (-1130 1425);
FORCEPROP 0 LAST $SEC 1
J 0
(-1125 1475);
DISPLAY 0.680851 (-1125 1475);
PAINT MONO (-1125 1475);
DISPLAY INVISIBLE (-1125 1475);
FORCEPROP 0 LAST CDS_SEC 1
J 0
(-1125 1475);
DISPLAY 0.680851 (-1125 1475);
DISPLAY INVISIBLE (-1125 1475);
FORCEPROP 1 LASTPIN (-1175 1400) $PN 1
J 0
(-1170 1362);
DISPLAY 0.787234 (-1170 1362);
PAINT MONO (-1170 1362);
FORCEPROP 1 LASTPIN (-1175 1200) $PN 2
J 0
(-1170 1210);
DISPLAY 0.787234 (-1170 1210);
PAINT MONO (-1170 1210);
FORCEPROP 1 LAST PACK_TYPE 0201LF
J 0
(-1125 1150);
DISPLAY 0.787234 (-1125 1150);
FORCEPROP 1 LAST VALUE 4.7K
J 0
(-1130 1375);
DISPLAY 0.787234 (-1130 1375);
FORCEPROP 1 LAST MATERIAL EMPTY
J 0
(-1135 1225);
DISPLAY 0.787234 (-1135 1225);
PAINT RED (-1135 1225);
FORCEPROP 1 LAST TOLERANCE 5%
J 0
(-1130 1325);
DISPLAY 0.787234 (-1130 1325);
FORCEPROP 1 LAST WATTAGE 1/20W
J 0
(-1135 1275);
DISPLAY 0.787234 (-1135 1275);
FORCEPROP 2 LAST CDS_LIB pure_quanta
J 0
(-1175 1300);
DISPLAY INVISIBLE (-1175 1300);
FORCEPROP 1 LAST PATH I117
J 0
(-1125 1475);
DISPLAY 0.978723 (-1125 1475);
PAINT WHITE (-1125 1475);
DISPLAY INVISIBLE (-1125 1475);
FORCEPROP 1 LAST PART_NUMBER CS24701JE04
J 0
(-1135 1175);
DISPLAY 0.978723 (-1135 1175);
DISPLAY INVISIBLE (-1135 1175);
FORCEADD Q_RES..2
(-900 1300);
FORCEPROP 1 LAST LOCATION R1478
J 0
(-855 1425);
DISPLAY 0.978723 (-855 1425);
FORCEPROP 0 LAST $SEC 1
J 0
(-850 1475);
DISPLAY 0.680851 (-850 1475);
PAINT MONO (-850 1475);
DISPLAY INVISIBLE (-850 1475);
FORCEPROP 0 LAST CDS_SEC 1
J 0
(-850 1475);
DISPLAY 0.680851 (-850 1475);
DISPLAY INVISIBLE (-850 1475);
FORCEPROP 1 LASTPIN (-900 1400) $PN 1
J 0
(-895 1362);
DISPLAY 0.787234 (-895 1362);
PAINT MONO (-895 1362);
FORCEPROP 1 LASTPIN (-900 1200) $PN 2
J 0
(-895 1210);
DISPLAY 0.787234 (-895 1210);
PAINT MONO (-895 1210);
FORCEPROP 1 LAST VALUE 1K
J 0
(-855 1375);
DISPLAY 0.787234 (-855 1375);
FORCEPROP 1 LAST TOLERANCE 1%
J 0
(-855 1325);
DISPLAY 0.787234 (-855 1325);
FORCEPROP 1 LAST WATTAGE 1/20W
J 0
(-860 1275);
DISPLAY 0.787234 (-860 1275);
FORCEPROP 1 LAST PACK_TYPE 0201LF
J 0
(-860 1125);
DISPLAY 0.787234 (-860 1125);
FORCEPROP 1 LAST MATERIAL EMPTY
J 0
(-860 1225);
DISPLAY 0.787234 (-860 1225);
PAINT RED (-860 1225);
FORCEPROP 2 LAST CDS_LIB pure_quanta
J 0
(-900 1300);
DISPLAY INVISIBLE (-900 1300);
FORCEPROP 1 LAST PATH I118
J 0
(-850 1475);
DISPLAY 0.978723 (-850 1475);
PAINT WHITE (-850 1475);
DISPLAY INVISIBLE (-850 1475);
FORCEPROP 1 LAST PART_NUMBER CS21001FE07
J 0
(-860 1175);
DISPLAY 0.978723 (-860 1175);
DISPLAY INVISIBLE (-860 1175);
FORCEADD GND..1
(-625 375);
FORCEPROP 3 LASTPIN (-625 425) SIG_NAME GND\g
J 0
(-615 435);
DISPLAY 0.659574 (-615 435);
PAINT MONO (-615 435);
DISPLAY INVISIBLE (-615 435);
FORCEPROP 1 LAST SIZE 1B
J 0
(-550 325);
DISPLAY 0.851064 (-550 325);
PAINT GREEN (-550 325);
DISPLAY INVISIBLE (-550 325);
FORCEPROP 2 LAST BOM_COST MEM
J 0
(-725 450);
DISPLAY 0.808511 (-725 450);
DISPLAY INVISIBLE (-725 450);
FORCEPROP 2 LAST CDS_LIB pure_quanta_power
J 0
(-625 375);
DISPLAY INVISIBLE (-625 375);
FORCEPROP 1 LAST HDL_POWER GND
J 0
(-625 525);
DISPLAY 0.851064 (-625 525);
PAINT GREEN (-625 525);
DISPLAY INVISIBLE (-625 525);
FORCEPROP 1 LAST PATH I119
J 0
(-550 375);
DISPLAY 0.872340 (-550 375);
PAINT AQUA (-550 375);
DISPLAY INVISIBLE (-550 375);
FORCEADD P1V0..1
(-8975 6300);
FORCEPROP 3 LASTPIN (-8975 6250) SIG_NAME P1V8_CPU0_RT_1D\g
J 0
(-8965 6260);
DISPLAY 0.659574 (-8965 6260);
PAINT MONO (-8965 6260);
DISPLAY INVISIBLE (-8965 6260);
FORCEPROP 1 LAST HDL_POWER P1V8_CPU0_RT_1D
J 1
(-8975 6350);
DISPLAY 0.489362 (-8975 6350);
PAINT SKYBLUE (-8975 6350);
FORCEPROP 2 LAST CDS_LIB pure_quanta_power
J 0
(-8975 6300);
DISPLAY INVISIBLE (-8975 6300);
FORCEPROP 1 LAST PATH I12
J 0
(-8925 6325);
DISPLAY 0.872340 (-8925 6325);
PAINT AQUA (-8925 6325);
DISPLAY INVISIBLE (-8925 6325);
FORCEADD Q_RES..2
(-625 675);
FORCEPROP 1 LAST LOCATION R1401
J 0
(-580 800);
DISPLAY 0.787234 (-580 800);
FORCEPROP 0 LAST $SEC 1
J 0
(-575 850);
DISPLAY 0.680851 (-575 850);
PAINT MONO (-575 850);
DISPLAY INVISIBLE (-575 850);
FORCEPROP 0 LAST CDS_SEC 1
J 0
(-575 850);
DISPLAY 0.680851 (-575 850);
DISPLAY INVISIBLE (-575 850);
FORCEPROP 1 LASTPIN (-625 775) $PN 1
J 0
(-620 737);
DISPLAY 0.787234 (-620 737);
PAINT MONO (-620 737);
FORCEPROP 1 LASTPIN (-625 575) $PN 2
J 0
(-620 585);
DISPLAY 0.787234 (-620 585);
PAINT MONO (-620 585);
FORCEPROP 1 LAST PACK_TYPE 0201LF
J 0
(-585 500);
DISPLAY 0.787234 (-585 500);
FORCEPROP 1 LAST MATERIAL CHIP
J 0
(-585 600);
DISPLAY 0.787234 (-585 600);
FORCEPROP 1 LAST WATTAGE 1/20W
J 0
(-585 650);
DISPLAY 0.787234 (-585 650);
FORCEPROP 1 LAST VALUE 4.7K
J 0
(-580 750);
DISPLAY 0.787234 (-580 750);
FORCEPROP 1 LAST TOLERANCE 5%
J 0
(-580 700);
DISPLAY 0.787234 (-580 700);
FORCEPROP 2 LAST CDS_LIB pure_quanta
J 0
(-625 675);
DISPLAY INVISIBLE (-625 675);
FORCEPROP 1 LAST PATH I120
J 0
(-575 850);
DISPLAY 0.978723 (-575 850);
PAINT WHITE (-575 850);
DISPLAY INVISIBLE (-575 850);
FORCEPROP 1 LAST PART_NUMBER CS24701JE04
J 0
(-585 550);
DISPLAY 0.978723 (-585 550);
DISPLAY INVISIBLE (-585 550);
FORCEADD Q_RES..2
(-625 1325);
FORCEPROP 1 LAST LOCATION R1479
J 0
(-580 1450);
DISPLAY 0.787234 (-580 1450);
FORCEPROP 0 LAST $SEC 1
J 0
(-575 1500);
DISPLAY 0.680851 (-575 1500);
PAINT MONO (-575 1500);
DISPLAY INVISIBLE (-575 1500);
FORCEPROP 0 LAST CDS_SEC 1
J 0
(-575 1500);
DISPLAY 0.680851 (-575 1500);
DISPLAY INVISIBLE (-575 1500);
FORCEPROP 1 LASTPIN (-625 1425) $PN 1
J 0
(-620 1387);
DISPLAY 0.787234 (-620 1387);
PAINT MONO (-620 1387);
FORCEPROP 1 LASTPIN (-625 1225) $PN 2
J 0
(-620 1235);
DISPLAY 0.787234 (-620 1235);
PAINT MONO (-620 1235);
FORCEPROP 1 LAST WATTAGE 1/20W
J 0
(-585 1300);
DISPLAY 0.787234 (-585 1300);
FORCEPROP 1 LAST MATERIAL EMPTY
J 0
(-585 1250);
DISPLAY 0.787234 (-585 1250);
PAINT RED (-585 1250);
FORCEPROP 1 LAST TOLERANCE 5%
J 0
(-580 1350);
DISPLAY 0.787234 (-580 1350);
FORCEPROP 1 LAST PACK_TYPE 0201LF
J 0
(-575 1175);
DISPLAY 0.787234 (-575 1175);
FORCEPROP 1 LAST VALUE 4.7K
J 0
(-580 1400);
DISPLAY 0.787234 (-580 1400);
FORCEPROP 2 LAST CDS_LIB pure_quanta
J 2
(-625 1325);
DISPLAY INVISIBLE (-625 1325);
FORCEPROP 1 LAST PATH I121
J 0
(-575 1500);
DISPLAY 0.978723 (-575 1500);
PAINT WHITE (-575 1500);
DISPLAY INVISIBLE (-575 1500);
FORCEPROP 1 LAST PART_NUMBER CS24701JE04
J 0
(-585 1200);
DISPLAY 0.978723 (-585 1200);
DISPLAY INVISIBLE (-585 1200);
FORCEADD P1V0..1
(-625 1625);
FORCEPROP 3 LASTPIN (-625 1575) SIG_NAME P1V8_CPU0_RT_1D\g
J 0
(-615 1585);
DISPLAY 0.659574 (-615 1585);
PAINT MONO (-615 1585);
DISPLAY INVISIBLE (-615 1585);
FORCEPROP 1 LAST HDL_POWER P1V8_CPU0_RT_1D
J 1
(-625 1675);
DISPLAY 0.489362 (-625 1675);
PAINT SKYBLUE (-625 1675);
FORCEPROP 2 LAST CDS_LIB pure_quanta_power
J 0
(-625 1625);
DISPLAY INVISIBLE (-625 1625);
FORCEPROP 1 LAST PATH I122
J 0
(-575 1650);
DISPLAY 0.872340 (-575 1650);
PAINT AQUA (-575 1650);
DISPLAY INVISIBLE (-575 1650);
FORCEADD OFFPAGE..1
R 2
(-2750 3550);
FORCEPROP 2 LAST $XR0 299 
J 0
(-2564 3550);
DISPLAY 0.638298 (-2564 3550);
PAINT MONO (-2564 3550);
FORCEPROP 2 LAST CDS_LIB standard
J 0
(-2750 3550);
DISPLAY INVISIBLE (-2750 3550);
FORCEPROP 1 LAST OFFPAGE TRUE
J 2
(-3075 3425);
DISPLAY 0.872340 (-3075 3425);
DISPLAY INVISIBLE (-3075 3425);
FORCEPROP 1 LAST COMMENT_BODY TRUE
J 2
(-2875 3450);
DISPLAY 0.872340 (-2875 3450);
PAINT GREEN (-2875 3450);
DISPLAY INVISIBLE (-2875 3450);
FORCEPROP 2 LAST PATH I125
J 0
(-2575 3625);
DISPLAY 0.680851 (-2575 3625);
DISPLAY INVISIBLE (-2575 3625);
FORCEADD OFFPAGE..1
R 2
(-2750 3450);
FORCEPROP 2 LAST $XR0 299 
J 0
(-2564 3450);
DISPLAY 0.638298 (-2564 3450);
PAINT MONO (-2564 3450);
FORCEPROP 2 LAST CDS_LIB standard
J 0
(-2750 3450);
DISPLAY INVISIBLE (-2750 3450);
FORCEPROP 1 LAST OFFPAGE TRUE
J 2
(-3075 3325);
DISPLAY 0.872340 (-3075 3325);
DISPLAY INVISIBLE (-3075 3325);
FORCEPROP 1 LAST COMMENT_BODY TRUE
J 2
(-2875 3350);
DISPLAY 0.872340 (-2875 3350);
PAINT GREEN (-2875 3350);
DISPLAY INVISIBLE (-2875 3350);
FORCEPROP 2 LAST PATH I126
J 0
(-2575 3525);
DISPLAY 0.680851 (-2575 3525);
DISPLAY INVISIBLE (-2575 3525);
FORCEADD OFFPAGE..1
R 2
(-2750 3350);
FORCEPROP 2 LAST $XR0 299 
J 0
(-2564 3350);
DISPLAY 0.638298 (-2564 3350);
PAINT MONO (-2564 3350);
FORCEPROP 2 LAST CDS_LIB standard
J 0
(-2750 3350);
DISPLAY INVISIBLE (-2750 3350);
FORCEPROP 1 LAST OFFPAGE TRUE
J 2
(-3075 3225);
DISPLAY 0.872340 (-3075 3225);
DISPLAY INVISIBLE (-3075 3225);
FORCEPROP 1 LAST COMMENT_BODY TRUE
J 2
(-2875 3250);
DISPLAY 0.872340 (-2875 3250);
PAINT GREEN (-2875 3250);
DISPLAY INVISIBLE (-2875 3250);
FORCEPROP 2 LAST PATH I127
J 0
(-2575 3425);
DISPLAY 0.680851 (-2575 3425);
DISPLAY INVISIBLE (-2575 3425);
FORCEADD OFFPAGE..1
R 2
(-2750 3250);
FORCEPROP 2 LAST $XR0 299 
J 0
(-2564 3250);
DISPLAY 0.638298 (-2564 3250);
PAINT MONO (-2564 3250);
FORCEPROP 2 LAST CDS_LIB standard
J 0
(-2750 3250);
DISPLAY INVISIBLE (-2750 3250);
FORCEPROP 1 LAST OFFPAGE TRUE
J 2
(-3075 3125);
DISPLAY 0.872340 (-3075 3125);
DISPLAY INVISIBLE (-3075 3125);
FORCEPROP 1 LAST COMMENT_BODY TRUE
J 2
(-2875 3150);
DISPLAY 0.872340 (-2875 3150);
PAINT GREEN (-2875 3150);
DISPLAY INVISIBLE (-2875 3150);
FORCEPROP 2 LAST PATH I128
J 0
(-2575 3325);
DISPLAY 0.680851 (-2575 3325);
DISPLAY INVISIBLE (-2575 3325);
FORCEADD OFFPAGE..3
R 2
(-7900 1450);
FORCEPROP 2 LAST $XR1 186 
J 0
(-8300 1450);
DISPLAY 0.638298 (-8300 1450);
PAINT MONO (-8300 1450);
FORCEPROP 2 LAST $XR0 185 
J 0
(-8180 1450);
DISPLAY 0.638298 (-8180 1450);
PAINT MONO (-8180 1450);
FORCEPROP 2 LAST CDS_LIB standard
J 0
(-7900 1450);
DISPLAY INVISIBLE (-7900 1450);
FORCEPROP 1 LAST OFFPAGE TRUE
J 2
(-8225 1325);
DISPLAY 0.872340 (-8225 1325);
PAINT GREEN (-8225 1325);
DISPLAY INVISIBLE (-8225 1325);
FORCEPROP 1 LAST COMMENT_BODY TRUE
J 2
(-7850 1350);
DISPLAY 0.872340 (-7850 1350);
PAINT GREEN (-7850 1350);
DISPLAY INVISIBLE (-7850 1350);
FORCEPROP 2 LAST PATH I13
J 0
(-8175 1500);
DISPLAY 0.680851 (-8175 1500);
DISPLAY INVISIBLE (-8175 1500);
FORCEADD OFFPAGE..5
(-7950 1550);
FORCEPROP 2 LAST $XR1 186 
J 0
(-8355 1550);
DISPLAY 0.638298 (-8355 1550);
PAINT MONO (-8355 1550);
FORCEPROP 2 LAST $XR0 185 
J 0
(-8235 1550);
DISPLAY 0.638298 (-8235 1550);
PAINT MONO (-8235 1550);
FORCEPROP 2 LAST CDS_LIB standard
J 0
(-7950 1550);
DISPLAY INVISIBLE (-7950 1550);
FORCEPROP 1 LAST OFFPAGE TRUE
J 0
(-7625 1425);
DISPLAY 0.872340 (-7625 1425);
PAINT GREEN (-7625 1425);
DISPLAY INVISIBLE (-7625 1425);
FORCEPROP 1 LAST COMMENT_BODY TRUE
J 0
(-7850 1475);
DISPLAY 0.872340 (-7850 1475);
PAINT GREEN (-7850 1475);
DISPLAY INVISIBLE (-7850 1475);
FORCEPROP 2 LAST PATH I14
J 0
(-8200 1600);
DISPLAY 0.680851 (-8200 1600);
DISPLAY INVISIBLE (-8200 1600);
FORCEADD UNIVERSAL_GND..1
(-6325 300);
FORCEPROP 3 LASTPIN (-6325 350) SIG_NAME GND\g
J 0
(-6315 360);
DISPLAY 0.659574 (-6315 360);
PAINT MONO (-6315 360);
DISPLAY INVISIBLE (-6315 360);
FORCEPROP 2 LAST CDS_LIB pure_quanta_power
J 0
(-6325 300);
DISPLAY INVISIBLE (-6325 300);
FORCEPROP 1 LAST HDL_POWER GND
J 1
(-6300 225);
DISPLAY 0.872340 (-6300 225);
PAINT GREEN (-6300 225);
DISPLAY INVISIBLE (-6300 225);
FORCEPROP 1 LAST PATH I15
J 0
(-6250 300);
DISPLAY 0.872340 (-6250 300);
PAINT AQUA (-6250 300);
DISPLAY INVISIBLE (-6250 300);
FORCEADD UNIVERSAL_GND..1
(-6175 300);
FORCEPROP 3 LASTPIN (-6175 350) SIG_NAME GND\g
J 0
(-6165 360);
DISPLAY 0.659574 (-6165 360);
PAINT MONO (-6165 360);
DISPLAY INVISIBLE (-6165 360);
FORCEPROP 2 LAST CDS_LIB pure_quanta_power
J 0
(-6175 300);
DISPLAY INVISIBLE (-6175 300);
FORCEPROP 1 LAST HDL_POWER GND
J 1
(-6150 225);
DISPLAY 0.872340 (-6150 225);
PAINT GREEN (-6150 225);
DISPLAY INVISIBLE (-6150 225);
FORCEPROP 1 LAST PATH I16
J 0
(-6100 300);
DISPLAY 0.872340 (-6100 300);
PAINT AQUA (-6100 300);
DISPLAY INVISIBLE (-6100 300);
FORCEADD Q_RES..2
R 2
(-6325 625);
FORCEPROP 1 LAST LOCATION R631
J 2
(-6370 750);
DISPLAY 0.978723 (-6370 750);
PAINT SKYBLUE (-6370 750);
FORCEPROP 0 LAST $SEC 1
J 0
(-6350 800);
DISPLAY 0.680851 (-6350 800);
PAINT MONO (-6350 800);
DISPLAY INVISIBLE (-6350 800);
FORCEPROP 0 LAST CDS_SEC 1
J 0
(-6350 800);
DISPLAY 0.680851 (-6350 800);
DISPLAY INVISIBLE (-6350 800);
FORCEPROP 1 LASTPIN (-6325 725) $PN 1
J 2
(-6330 687);
DISPLAY 0.787234 (-6330 687);
PAINT MONO (-6330 687);
FORCEPROP 1 LASTPIN (-6325 525) $PN 2
J 2
(-6330 535);
DISPLAY 0.787234 (-6330 535);
PAINT MONO (-6330 535);
FORCEPROP 1 LAST PACK_TYPE 0201LF
J 2
(-6365 450);
DISPLAY 0.978723 (-6365 450);
FORCEPROP 1 LAST MATERIAL EMPTY
J 2
(-6365 550);
DISPLAY 0.978723 (-6365 550);
FORCEPROP 1 LAST WATTAGE 1/20W
J 2
(-6365 600);
DISPLAY 0.978723 (-6365 600);
FORCEPROP 1 LAST VALUE 51.1
J 2
(-6370 700);
DISPLAY 0.978723 (-6370 700);
FORCEPROP 1 LAST TOLERANCE 1%
J 2
(-6370 650);
DISPLAY 0.978723 (-6370 650);
FORCEPROP 2 LAST CDS_LIB pure_quanta
J 0
(-6325 625);
DISPLAY INVISIBLE (-6325 625);
FORCEPROP 1 LAST PATH I17
J 2
(-6375 800);
DISPLAY 0.978723 (-6375 800);
PAINT WHITE (-6375 800);
DISPLAY INVISIBLE (-6375 800);
FORCEPROP 1 LAST PART_NUMBER CS05111FE00
J 2
(-6365 500);
DISPLAY 0.978723 (-6365 500);
DISPLAY INVISIBLE (-6365 500);
FORCEADD Q_RES..2
(-6175 625);
FORCEPROP 1 LAST LOCATION R634
J 0
(-6130 750);
DISPLAY 0.978723 (-6130 750);
PAINT SKYBLUE (-6130 750);
FORCEPROP 0 LAST $SEC 1
J 0
(-6125 800);
DISPLAY 0.680851 (-6125 800);
PAINT MONO (-6125 800);
DISPLAY INVISIBLE (-6125 800);
FORCEPROP 0 LAST CDS_SEC 1
J 0
(-6125 800);
DISPLAY 0.680851 (-6125 800);
DISPLAY INVISIBLE (-6125 800);
FORCEPROP 1 LASTPIN (-6175 725) $PN 1
J 0
(-6170 687);
DISPLAY 0.787234 (-6170 687);
PAINT MONO (-6170 687);
FORCEPROP 1 LASTPIN (-6175 525) $PN 2
J 0
(-6170 535);
DISPLAY 0.787234 (-6170 535);
PAINT MONO (-6170 535);
FORCEPROP 1 LAST VALUE 51.1
J 0
(-6130 700);
DISPLAY 0.978723 (-6130 700);
FORCEPROP 1 LAST WATTAGE 1/20W
J 0
(-6135 600);
DISPLAY 0.978723 (-6135 600);
FORCEPROP 1 LAST MATERIAL EMPTY
J 0
(-6135 550);
DISPLAY 0.978723 (-6135 550);
FORCEPROP 1 LAST PACK_TYPE 0201LF
J 0
(-6135 450);
DISPLAY 0.978723 (-6135 450);
FORCEPROP 1 LAST TOLERANCE 1%
J 0
(-6130 650);
DISPLAY 0.978723 (-6130 650);
FORCEPROP 2 LAST CDS_LIB pure_quanta
J 0
(-6175 625);
DISPLAY INVISIBLE (-6175 625);
FORCEPROP 1 LAST PATH I18
J 0
(-6125 800);
DISPLAY 0.978723 (-6125 800);
PAINT WHITE (-6125 800);
DISPLAY INVISIBLE (-6125 800);
FORCEPROP 1 LAST PART_NUMBER CS05111FE00
J 0
(-6135 500);
DISPLAY 0.978723 (-6135 500);
DISPLAY INVISIBLE (-6135 500);
FORCEADD Q_RES..1
(-6625 1100);
FORCEPROP 1 LAST LOCATION R613
J 0
(-6875 1100);
DISPLAY 0.978723 (-6875 1100);
PAINT SKYBLUE (-6875 1100);
FORCEPROP 2 LAST SEC 1
J 0
(-6675 1300);
DISPLAY 0.680851 (-6675 1300);
PAINT MONO (-6675 1300);
DISPLAY INVISIBLE (-6675 1300);
FORCEPROP 1 LASTPIN (-6725 1100) $PN 1
J 0
(-6713 1112);
DISPLAY 0.787234 (-6713 1112);
PAINT MONO (-6713 1112);
FORCEPROP 1 LASTPIN (-6525 1100) $PN 2
J 0
(-6563 1112);
DISPLAY 0.787234 (-6563 1112);
PAINT MONO (-6563 1112);
FORCEPROP 1 LAST WATTAGE 1/20W
J 2
(-6825 1175);
DISPLAY 0.787234 (-6825 1175);
FORCEPROP 1 LAST MATERIAL CHIP
J 0
(-6800 1175);
DISPLAY 0.787234 (-6800 1175);
FORCEPROP 1 LAST TOLERANCE 5%
J 0
(-6800 1225);
DISPLAY 0.787234 (-6800 1225);
FORCEPROP 1 LAST VALUE 0
J 2
(-6825 1225);
DISPLAY 0.787234 (-6825 1225);
FORCEPROP 1 LAST PACK_TYPE 0201LF
J 0
(-6600 1175);
DISPLAY 0.787234 (-6600 1175);
FORCEPROP 0 LAST SEC_TYPE 0201LF
J 0
(-6675 1300);
DISPLAY 0.680851 (-6675 1300);
DISPLAY INVISIBLE (-6675 1300);
FORCEPROP 2 LAST CDS_LIB pure_quanta
J 0
(-6625 1100);
DISPLAY INVISIBLE (-6625 1100);
FORCEPROP 1 LAST PATH I19
J 0
(-6675 1250);
DISPLAY 0.978723 (-6675 1250);
PAINT WHITE (-6675 1250);
DISPLAY INVISIBLE (-6675 1250);
FORCEPROP 1 LAST PART_NUMBER CS00001JE10
J 0
(-6675 1225);
DISPLAY 0.808511 (-6675 1225);
DISPLAY INVISIBLE (-6675 1225);
FORCEADD OFFPAGE..1
(-8075 1100);
FORCEPROP 2 LAST $XR0 182 
J 0
(-8327 1100);
DISPLAY 0.638298 (-8327 1100);
PAINT MONO (-8327 1100);
FORCEPROP 2 LAST CDS_LIB standard
J 0
(-8075 1100);
DISPLAY INVISIBLE (-8075 1100);
FORCEPROP 1 LAST OFFPAGE TRUE
J 0
(-7750 975);
DISPLAY 0.872340 (-7750 975);
DISPLAY INVISIBLE (-7750 975);
FORCEPROP 1 LAST COMMENT_BODY TRUE
J 0
(-7950 1000);
DISPLAY 0.872340 (-7950 1000);
PAINT GREEN (-7950 1000);
DISPLAY INVISIBLE (-7950 1000);
FORCEPROP 2 LAST PATH I2
J 0
(-8350 1150);
DISPLAY 0.680851 (-8350 1150);
DISPLAY INVISIBLE (-8350 1150);
FORCEADD Q_RES..1
(-6625 950);
FORCEPROP 1 LAST LOCATION R614
J 0
(-6875 950);
DISPLAY 0.978723 (-6875 950);
PAINT SKYBLUE (-6875 950);
FORCEPROP 2 LAST SEC 1
J 0
(-6675 1150);
DISPLAY 0.680851 (-6675 1150);
PAINT MONO (-6675 1150);
DISPLAY INVISIBLE (-6675 1150);
FORCEPROP 1 LASTPIN (-6725 950) $PN 1
J 0
(-6713 962);
DISPLAY 0.787234 (-6713 962);
PAINT MONO (-6713 962);
FORCEPROP 1 LASTPIN (-6525 950) $PN 2
J 0
(-6563 962);
DISPLAY 0.787234 (-6563 962);
PAINT MONO (-6563 962);
FORCEPROP 1 LAST PACK_TYPE 0201LF
J 0
(-6600 1025);
DISPLAY 0.787234 (-6600 1025);
FORCEPROP 1 LAST MATERIAL CHIP
J 0
(-6800 1025);
DISPLAY 0.787234 (-6800 1025);
FORCEPROP 2 LAST SEC_TYPE 0201LF
J 0
(-6675 1150);
DISPLAY 0.680851 (-6675 1150);
DISPLAY INVISIBLE (-6675 1150);
FORCEPROP 1 LAST WATTAGE 1/20W
J 2
(-6825 1025);
DISPLAY 0.787234 (-6825 1025);
DISPLAY INVISIBLE (-6825 1025);
FORCEPROP 1 LAST VALUE 0
J 2
(-6825 1075);
DISPLAY 0.787234 (-6825 1075);
DISPLAY INVISIBLE (-6825 1075);
FORCEPROP 1 LAST TOLERANCE 5%
J 0
(-6800 1075);
DISPLAY 0.787234 (-6800 1075);
DISPLAY INVISIBLE (-6800 1075);
FORCEPROP 2 LAST CDS_LIB pure_quanta
J 0
(-6625 950);
DISPLAY INVISIBLE (-6625 950);
FORCEPROP 1 LAST PATH I20
J 0
(-6675 1100);
DISPLAY 0.978723 (-6675 1100);
PAINT WHITE (-6675 1100);
DISPLAY INVISIBLE (-6675 1100);
FORCEPROP 1 LAST PART_NUMBER CS00001JE10
J 0
(-6675 1075);
DISPLAY 0.808511 (-6675 1075);
DISPLAY INVISIBLE (-6675 1075);
FORCEADD Q_RES..1
(-6350 1450);
FORCEPROP 1 LAST LOCATION R681
J 0
(-6600 1475);
DISPLAY 0.978723 (-6600 1475);
PAINT SKYBLUE (-6600 1475);
FORCEPROP 0 LAST $SEC 1
J 0
(-6500 1525);
DISPLAY 0.680851 (-6500 1525);
PAINT MONO (-6500 1525);
DISPLAY INVISIBLE (-6500 1525);
FORCEPROP 0 LAST CDS_SEC 1
J 0
(-6500 1525);
DISPLAY 0.680851 (-6500 1525);
DISPLAY INVISIBLE (-6500 1525);
FORCEPROP 1 LASTPIN (-6450 1450) $PN 1
J 0
(-6438 1462);
DISPLAY 0.787234 (-6438 1462);
PAINT MONO (-6438 1462);
FORCEPROP 1 LASTPIN (-6250 1450) $PN 2
J 0
(-6288 1462);
DISPLAY 0.787234 (-6288 1462);
PAINT MONO (-6288 1462);
FORCEPROP 1 LAST PACK_TYPE 0201LF
J 0
(-6325 1525);
DISPLAY 0.787234 (-6325 1525);
DISPLAY INVISIBLE (-6325 1525);
FORCEPROP 1 LAST WATTAGE 1/20W
J 2
(-6550 1525);
DISPLAY 0.787234 (-6550 1525);
DISPLAY INVISIBLE (-6550 1525);
FORCEPROP 1 LAST MATERIAL CHIP
J 0
(-6525 1525);
DISPLAY 0.787234 (-6525 1525);
DISPLAY INVISIBLE (-6525 1525);
FORCEPROP 2 LAST CDS_LIB pure_quanta
J 0
(-6350 1450);
DISPLAY INVISIBLE (-6350 1450);
FORCEPROP 1 LAST VALUE 49.9
J 2
(-6550 1575);
DISPLAY 0.787234 (-6550 1575);
DISPLAY INVISIBLE (-6550 1575);
FORCEPROP 1 LAST TOLERANCE 1%
J 0
(-6525 1575);
DISPLAY 0.787234 (-6525 1575);
DISPLAY INVISIBLE (-6525 1575);
FORCEPROP 1 LAST PATH I21
J 0
(-6400 1600);
DISPLAY 0.978723 (-6400 1600);
PAINT WHITE (-6400 1600);
DISPLAY INVISIBLE (-6400 1600);
FORCEPROP 1 LAST PART_NUMBER CS04991FE06
J 0
(-6400 1575);
DISPLAY 0.808511 (-6400 1575);
DISPLAY INVISIBLE (-6400 1575);
FORCEADD Q_RES..1
(-6350 1550);
FORCEPROP 1 LAST LOCATION R680
J 0
(-6600 1575);
DISPLAY 0.978723 (-6600 1575);
PAINT SKYBLUE (-6600 1575);
FORCEPROP 0 LAST $SEC 1
J 0
(-6400 1725);
DISPLAY 0.680851 (-6400 1725);
PAINT MONO (-6400 1725);
DISPLAY INVISIBLE (-6400 1725);
FORCEPROP 0 LAST CDS_SEC 1
J 0
(-6400 1725);
DISPLAY 0.680851 (-6400 1725);
DISPLAY INVISIBLE (-6400 1725);
FORCEPROP 1 LASTPIN (-6450 1550) $PN 1
J 0
(-6438 1562);
DISPLAY 0.787234 (-6438 1562);
PAINT MONO (-6438 1562);
FORCEPROP 1 LASTPIN (-6250 1550) $PN 2
J 0
(-6288 1562);
DISPLAY 0.787234 (-6288 1562);
PAINT MONO (-6288 1562);
FORCEPROP 1 LAST WATTAGE 1/20W
J 2
(-6550 1625);
DISPLAY 0.787234 (-6550 1625);
FORCEPROP 1 LAST MATERIAL CHIP
J 0
(-6525 1625);
DISPLAY 0.787234 (-6525 1625);
FORCEPROP 1 LAST PACK_TYPE 0201LF
J 0
(-6325 1625);
DISPLAY 0.787234 (-6325 1625);
FORCEPROP 1 LAST VALUE 49.9
J 2
(-6550 1675);
DISPLAY 0.787234 (-6550 1675);
FORCEPROP 1 LAST TOLERANCE 1%
J 0
(-6525 1675);
DISPLAY 0.787234 (-6525 1675);
FORCEPROP 2 LAST CDS_LIB pure_quanta
J 0
(-6350 1550);
DISPLAY INVISIBLE (-6350 1550);
FORCEPROP 1 LAST PATH I22
J 0
(-6400 1700);
DISPLAY 0.978723 (-6400 1700);
PAINT WHITE (-6400 1700);
DISPLAY INVISIBLE (-6400 1700);
FORCEPROP 1 LAST PART_NUMBER CS04991FE06
J 0
(-6400 1675);
DISPLAY 0.808511 (-6400 1675);
DISPLAY INVISIBLE (-6400 1675);
FORCEADD OFFPAGE..1
(-6175 1850);
FORCEPROP 2 LAST $XR0 299 
J 0
(-6427 1850);
DISPLAY 0.638298 (-6427 1850);
PAINT MONO (-6427 1850);
FORCEPROP 2 LAST CDS_LIB standard
J 0
(-6175 1850);
DISPLAY INVISIBLE (-6175 1850);
FORCEPROP 1 LAST OFFPAGE TRUE
J 0
(-5850 1725);
DISPLAY 0.872340 (-5850 1725);
DISPLAY INVISIBLE (-5850 1725);
FORCEPROP 1 LAST COMMENT_BODY TRUE
J 0
(-6050 1750);
DISPLAY 0.872340 (-6050 1750);
PAINT GREEN (-6050 1750);
DISPLAY INVISIBLE (-6050 1750);
FORCEPROP 2 LAST PATH I23
J 0
(-6425 1900);
DISPLAY 0.680851 (-6425 1900);
DISPLAY INVISIBLE (-6425 1900);
FORCEADD OFFPAGE..1
(-6175 1950);
FORCEPROP 2 LAST $XR0 299 
J 0
(-6427 1950);
DISPLAY 0.638298 (-6427 1950);
PAINT MONO (-6427 1950);
FORCEPROP 2 LAST CDS_LIB standard
J 0
(-6175 1950);
DISPLAY INVISIBLE (-6175 1950);
FORCEPROP 1 LAST OFFPAGE TRUE
J 0
(-5850 1825);
DISPLAY 0.872340 (-5850 1825);
DISPLAY INVISIBLE (-5850 1825);
FORCEPROP 1 LAST COMMENT_BODY TRUE
J 0
(-6050 1850);
DISPLAY 0.872340 (-6050 1850);
PAINT GREEN (-6050 1850);
DISPLAY INVISIBLE (-6050 1850);
FORCEPROP 2 LAST PATH I24
J 0
(-6425 2000);
DISPLAY 0.680851 (-6425 2000);
DISPLAY INVISIBLE (-6425 2000);
FORCEADD OFFPAGE..3
R 2
(-7675 2700);
FORCEPROP 2 LAST $XR0 184 
J 0
(-7955 2700);
DISPLAY 0.638298 (-7955 2700);
PAINT MONO (-7955 2700);
FORCEPROP 2 LAST CDS_LIB standard
J 0
(-7675 2700);
DISPLAY INVISIBLE (-7675 2700);
FORCEPROP 1 LAST OFFPAGE TRUE
J 2
(-8000 2575);
DISPLAY 0.872340 (-8000 2575);
PAINT GREEN (-8000 2575);
DISPLAY INVISIBLE (-8000 2575);
FORCEPROP 1 LAST COMMENT_BODY TRUE
J 2
(-7625 2600);
DISPLAY 0.872340 (-7625 2600);
PAINT GREEN (-7625 2600);
DISPLAY INVISIBLE (-7625 2600);
FORCEPROP 2 LAST PATH I25
J 0
(-7950 2750);
DISPLAY 0.680851 (-7950 2750);
DISPLAY INVISIBLE (-7950 2750);
FORCEADD OFFPAGE..1
(-7675 2800);
FORCEPROP 2 LAST $XR0 184 
J 0
(-7927 2800);
DISPLAY 0.638298 (-7927 2800);
PAINT MONO (-7927 2800);
FORCEPROP 2 LAST CDS_LIB standard
J 0
(-7675 2800);
DISPLAY INVISIBLE (-7675 2800);
FORCEPROP 1 LAST OFFPAGE TRUE
J 0
(-7350 2675);
DISPLAY 0.872340 (-7350 2675);
DISPLAY INVISIBLE (-7350 2675);
FORCEPROP 1 LAST COMMENT_BODY TRUE
J 0
(-7550 2700);
DISPLAY 0.872340 (-7550 2700);
PAINT GREEN (-7550 2700);
DISPLAY INVISIBLE (-7550 2700);
FORCEPROP 2 LAST PATH I26
J 0
(-7925 2850);
DISPLAY 0.680851 (-7925 2850);
DISPLAY INVISIBLE (-7925 2850);
FORCEADD OFFPAGE..5
R 2
(-7825 3800);
FORCEPROP 2 LAST $XR0 299 
J 0
(-7636 3800);
DISPLAY 0.638298 (-7636 3800);
PAINT MONO (-7636 3800);
FORCEPROP 2 LAST CDS_LIB standard
J 0
(-7825 3800);
DISPLAY INVISIBLE (-7825 3800);
FORCEPROP 1 LAST OFFPAGE TRUE
J 2
(-8150 3675);
DISPLAY 0.872340 (-8150 3675);
PAINT GREEN (-8150 3675);
DISPLAY INVISIBLE (-8150 3675);
FORCEPROP 1 LAST COMMENT_BODY TRUE
J 2
(-7925 3725);
DISPLAY 0.872340 (-7925 3725);
PAINT GREEN (-7925 3725);
DISPLAY INVISIBLE (-7925 3725);
FORCEPROP 2 LAST PATH I27
J 0
(-7625 3850);
DISPLAY 0.680851 (-7625 3850);
DISPLAY INVISIBLE (-7625 3850);
FORCEADD OFFPAGE..1
(-6175 2050);
FORCEPROP 2 LAST $XR0 299 
J 0
(-6427 2050);
DISPLAY 0.638298 (-6427 2050);
PAINT MONO (-6427 2050);
FORCEPROP 2 LAST CDS_LIB standard
J 0
(-6175 2050);
DISPLAY INVISIBLE (-6175 2050);
FORCEPROP 1 LAST OFFPAGE TRUE
J 0
(-5850 1925);
DISPLAY 0.872340 (-5850 1925);
DISPLAY INVISIBLE (-5850 1925);
FORCEPROP 1 LAST COMMENT_BODY TRUE
J 0
(-6050 1950);
DISPLAY 0.872340 (-6050 1950);
PAINT GREEN (-6050 1950);
DISPLAY INVISIBLE (-6050 1950);
FORCEPROP 2 LAST PATH I28
J 0
(-6425 2100);
DISPLAY 0.680851 (-6425 2100);
DISPLAY INVISIBLE (-6425 2100);
FORCEADD Q_RES..1
(-6375 2800);
FORCEPROP 1 LAST LOCATION R1067
J 0
(-6625 2825);
DISPLAY 0.978723 (-6625 2825);
FORCEPROP 0 LAST $SEC 1
J 0
(-6425 2975);
DISPLAY 0.680851 (-6425 2975);
PAINT MONO (-6425 2975);
DISPLAY INVISIBLE (-6425 2975);
FORCEPROP 0 LAST CDS_SEC 1
J 0
(-6425 2975);
DISPLAY 0.680851 (-6425 2975);
DISPLAY INVISIBLE (-6425 2975);
FORCEPROP 1 LASTPIN (-6475 2800) $PN 1
J 0
(-6463 2812);
DISPLAY 0.787234 (-6463 2812);
PAINT MONO (-6463 2812);
FORCEPROP 1 LASTPIN (-6275 2800) $PN 2
J 0
(-6313 2812);
DISPLAY 0.787234 (-6313 2812);
PAINT MONO (-6313 2812);
FORCEPROP 1 LAST MATERIAL CHIP
J 0
(-6550 2875);
DISPLAY 0.787234 (-6550 2875);
FORCEPROP 1 LAST WATTAGE 1/20W
J 2
(-6575 2875);
DISPLAY 0.787234 (-6575 2875);
FORCEPROP 1 LAST VALUE 0
J 2
(-6575 2925);
DISPLAY 0.787234 (-6575 2925);
FORCEPROP 1 LAST TOLERANCE 5%
J 0
(-6550 2925);
DISPLAY 0.787234 (-6550 2925);
FORCEPROP 1 LAST PACK_TYPE 0201LF
J 0
(-6350 2875);
DISPLAY 0.787234 (-6350 2875);
FORCEPROP 2 LAST CDS_LIB pure_quanta
J 0
(-6375 2800);
DISPLAY INVISIBLE (-6375 2800);
FORCEPROP 1 LAST PATH I29
J 0
(-6425 2950);
DISPLAY 0.978723 (-6425 2950);
PAINT WHITE (-6425 2950);
DISPLAY INVISIBLE (-6425 2950);
FORCEPROP 1 LAST PART_NUMBER CS00001JE10
J 0
(-6425 2925);
DISPLAY 0.808511 (-6425 2925);
DISPLAY INVISIBLE (-6425 2925);
FORCEADD UNIVERSAL_GND..1
(-9000 3075);
FORCEPROP 3 LASTPIN (-9000 3125) SIG_NAME GND\g
J 0
(-8990 3135);
DISPLAY 0.659574 (-8990 3135);
PAINT MONO (-8990 3135);
DISPLAY INVISIBLE (-8990 3135);
FORCEPROP 2 LAST CDS_LIB pure_quanta_power
J 0
(-9000 3075);
DISPLAY INVISIBLE (-9000 3075);
FORCEPROP 1 LAST HDL_POWER GND
J 1
(-8975 3000);
DISPLAY 0.872340 (-8975 3000);
PAINT GREEN (-8975 3000);
DISPLAY INVISIBLE (-8975 3000);
FORCEPROP 1 LAST PATH I3
J 0
(-8925 3075);
DISPLAY 0.872340 (-8925 3075);
PAINT AQUA (-8925 3075);
DISPLAY INVISIBLE (-8925 3075);
FORCEADD Q_RES..1
(-6375 2700);
FORCEPROP 1 LAST LOCATION R1068
J 0
(-6625 2725);
DISPLAY 0.978723 (-6625 2725);
FORCEPROP 0 LAST $SEC 1
J 0
(-6625 2775);
DISPLAY 0.680851 (-6625 2775);
PAINT MONO (-6625 2775);
DISPLAY INVISIBLE (-6625 2775);
FORCEPROP 0 LAST CDS_SEC 1
J 0
(-6625 2775);
DISPLAY 0.680851 (-6625 2775);
DISPLAY INVISIBLE (-6625 2775);
FORCEPROP 1 LASTPIN (-6475 2700) $PN 1
J 0
(-6463 2712);
DISPLAY 0.787234 (-6463 2712);
PAINT MONO (-6463 2712);
FORCEPROP 1 LASTPIN (-6275 2700) $PN 2
J 0
(-6313 2712);
DISPLAY 0.787234 (-6313 2712);
PAINT MONO (-6313 2712);
FORCEPROP 2 LAST CDS_LIB pure_quanta
J 0
(-6375 2700);
DISPLAY INVISIBLE (-6375 2700);
FORCEPROP 1 LAST PACK_TYPE 0201LF
J 0
(-6350 2775);
DISPLAY 0.787234 (-6350 2775);
DISPLAY INVISIBLE (-6350 2775);
FORCEPROP 1 LAST MATERIAL CHIP
J 0
(-6550 2775);
DISPLAY 0.787234 (-6550 2775);
DISPLAY INVISIBLE (-6550 2775);
FORCEPROP 1 LAST TOLERANCE 5%
J 0
(-6550 2825);
DISPLAY 0.787234 (-6550 2825);
DISPLAY INVISIBLE (-6550 2825);
FORCEPROP 1 LAST VALUE 0
J 2
(-6575 2825);
DISPLAY 0.787234 (-6575 2825);
DISPLAY INVISIBLE (-6575 2825);
FORCEPROP 1 LAST WATTAGE 1/20W
J 2
(-6575 2775);
DISPLAY 0.787234 (-6575 2775);
DISPLAY INVISIBLE (-6575 2775);
FORCEPROP 1 LAST PATH I30
J 0
(-6425 2850);
DISPLAY 0.978723 (-6425 2850);
PAINT WHITE (-6425 2850);
DISPLAY INVISIBLE (-6425 2850);
FORCEPROP 1 LAST PART_NUMBER CS00001JE10
J 0
(-6425 2825);
DISPLAY 0.808511 (-6425 2825);
DISPLAY INVISIBLE (-6425 2825);
FORCEADD OFFPAGE..1
(-6050 3250);
FORCEPROP 2 LAST $XR0 299 
J 0
(-6302 3250);
DISPLAY 0.638298 (-6302 3250);
PAINT MONO (-6302 3250);
FORCEPROP 2 LAST CDS_LIB standard
J 0
(-6050 3250);
DISPLAY INVISIBLE (-6050 3250);
FORCEPROP 1 LAST OFFPAGE TRUE
J 0
(-5725 3125);
DISPLAY 0.872340 (-5725 3125);
DISPLAY INVISIBLE (-5725 3125);
FORCEPROP 1 LAST COMMENT_BODY TRUE
J 0
(-5925 3150);
DISPLAY 0.872340 (-5925 3150);
PAINT GREEN (-5925 3150);
DISPLAY INVISIBLE (-5925 3150);
FORCEPROP 2 LAST PATH I31
J 0
(-6325 3300);
DISPLAY 0.680851 (-6325 3300);
DISPLAY INVISIBLE (-6325 3300);
FORCEADD OFFPAGE..1
(-6050 3150);
FORCEPROP 2 LAST $XR0 299 
J 0
(-6302 3150);
DISPLAY 0.638298 (-6302 3150);
PAINT MONO (-6302 3150);
FORCEPROP 2 LAST CDS_LIB standard
J 0
(-6050 3150);
DISPLAY INVISIBLE (-6050 3150);
FORCEPROP 1 LAST OFFPAGE TRUE
J 0
(-5725 3025);
DISPLAY 0.872340 (-5725 3025);
DISPLAY INVISIBLE (-5725 3025);
FORCEPROP 1 LAST COMMENT_BODY TRUE
J 0
(-5925 3050);
DISPLAY 0.872340 (-5925 3050);
PAINT GREEN (-5925 3050);
DISPLAY INVISIBLE (-5925 3050);
FORCEPROP 2 LAST PATH I32
J 0
(-6325 3200);
DISPLAY 0.680851 (-6325 3200);
DISPLAY INVISIBLE (-6325 3200);
FORCEADD OFFPAGE..1
(-6000 2350);
FORCEPROP 2 LAST $XR0 299 
J 0
(-6282 2350);
DISPLAY 0.638298 (-6282 2350);
PAINT MONO (-6282 2350);
FORCEPROP 2 LAST CDS_LIB standard
J 0
(-6000 2350);
DISPLAY INVISIBLE (-6000 2350);
FORCEPROP 1 LAST OFFPAGE TRUE
J 0
(-5675 2225);
DISPLAY 0.872340 (-5675 2225);
DISPLAY INVISIBLE (-5675 2225);
FORCEPROP 1 LAST COMMENT_BODY TRUE
J 0
(-5875 2250);
DISPLAY 0.872340 (-5875 2250);
PAINT GREEN (-5875 2250);
DISPLAY INVISIBLE (-5875 2250);
FORCEPROP 2 LAST PATH I33
J 0
(-6250 2400);
DISPLAY 0.680851 (-6250 2400);
DISPLAY INVISIBLE (-6250 2400);
FORCEADD OFFPAGE..1
(-6000 2450);
FORCEPROP 2 LAST $XR0 299 
J 0
(-6282 2450);
DISPLAY 0.638298 (-6282 2450);
PAINT MONO (-6282 2450);
FORCEPROP 2 LAST CDS_LIB standard
J 0
(-6000 2450);
DISPLAY INVISIBLE (-6000 2450);
FORCEPROP 1 LAST OFFPAGE TRUE
J 0
(-5675 2325);
DISPLAY 0.872340 (-5675 2325);
DISPLAY INVISIBLE (-5675 2325);
FORCEPROP 1 LAST COMMENT_BODY TRUE
J 0
(-5875 2350);
DISPLAY 0.872340 (-5875 2350);
PAINT GREEN (-5875 2350);
DISPLAY INVISIBLE (-5875 2350);
FORCEPROP 2 LAST PATH I34
J 0
(-6250 2500);
DISPLAY 0.680851 (-6250 2500);
DISPLAY INVISIBLE (-6250 2500);
FORCEADD OFFPAGE..1
(-6000 2550);
FORCEPROP 2 LAST $XR0 299 
J 0
(-6282 2550);
DISPLAY 0.638298 (-6282 2550);
PAINT MONO (-6282 2550);
FORCEPROP 2 LAST CDS_LIB standard
J 0
(-6000 2550);
DISPLAY INVISIBLE (-6000 2550);
FORCEPROP 1 LAST OFFPAGE TRUE
J 0
(-5675 2425);
DISPLAY 0.872340 (-5675 2425);
DISPLAY INVISIBLE (-5675 2425);
FORCEPROP 1 LAST COMMENT_BODY TRUE
J 0
(-5875 2450);
DISPLAY 0.872340 (-5875 2450);
PAINT GREEN (-5875 2450);
DISPLAY INVISIBLE (-5875 2450);
FORCEPROP 2 LAST PATH I35
J 0
(-6250 2600);
DISPLAY 0.680851 (-6250 2600);
DISPLAY INVISIBLE (-6250 2600);
FORCEADD Q_RES..2
(-8050 4925);
FORCEPROP 1 LAST LOCATION R1076
J 0
(-8005 5050);
DISPLAY 0.787234 (-8005 5050);
FORCEPROP 0 LAST $SEC 1
J 0
(-8000 5100);
DISPLAY 0.680851 (-8000 5100);
PAINT MONO (-8000 5100);
DISPLAY INVISIBLE (-8000 5100);
FORCEPROP 0 LAST CDS_SEC 1
J 0
(-8000 5100);
DISPLAY 0.680851 (-8000 5100);
DISPLAY INVISIBLE (-8000 5100);
FORCEPROP 1 LASTPIN (-8050 5025) $PN 1
J 0
(-8045 4987);
DISPLAY 0.787234 (-8045 4987);
PAINT MONO (-8045 4987);
FORCEPROP 1 LASTPIN (-8050 4825) $PN 2
J 0
(-8045 4835);
DISPLAY 0.787234 (-8045 4835);
PAINT MONO (-8045 4835);
FORCEPROP 1 LAST WATTAGE 1/20W
J 0
(-8010 4900);
DISPLAY 0.787234 (-8010 4900);
FORCEPROP 1 LAST TOLERANCE 5%
J 0
(-8005 4950);
DISPLAY 0.787234 (-8005 4950);
FORCEPROP 1 LAST PACK_TYPE 0201LF
J 0
(-8010 4750);
DISPLAY 0.787234 (-8010 4750);
FORCEPROP 1 LAST MATERIAL CHIP
J 0
(-8010 4850);
DISPLAY 0.787234 (-8010 4850);
FORCEPROP 1 LAST VALUE 4.7K
J 0
(-8005 5000);
DISPLAY 0.787234 (-8005 5000);
FORCEPROP 2 LAST CDS_LIB pure_quanta
J 0
(-8050 4925);
DISPLAY INVISIBLE (-8050 4925);
FORCEPROP 1 LAST PATH I36
J 0
(-8000 5100);
DISPLAY 0.978723 (-8000 5100);
PAINT WHITE (-8000 5100);
DISPLAY INVISIBLE (-8000 5100);
FORCEPROP 1 LAST PART_NUMBER CS24701JE04
J 0
(-8010 4800);
DISPLAY 0.978723 (-8010 4800);
DISPLAY INVISIBLE (-8010 4800);
FORCEADD Q_RES..2
(-7750 4925);
FORCEPROP 1 LAST LOCATION R1078
J 0
(-7705 5050);
DISPLAY 0.787234 (-7705 5050);
FORCEPROP 0 LAST $SEC 1
J 0
(-7700 5100);
DISPLAY 0.680851 (-7700 5100);
PAINT MONO (-7700 5100);
DISPLAY INVISIBLE (-7700 5100);
FORCEPROP 0 LAST CDS_SEC 1
J 0
(-7700 5100);
DISPLAY 0.680851 (-7700 5100);
DISPLAY INVISIBLE (-7700 5100);
FORCEPROP 1 LASTPIN (-7750 5025) $PN 1
J 0
(-7745 4987);
DISPLAY 0.787234 (-7745 4987);
PAINT MONO (-7745 4987);
FORCEPROP 1 LASTPIN (-7750 4825) $PN 2
J 0
(-7745 4835);
DISPLAY 0.787234 (-7745 4835);
PAINT MONO (-7745 4835);
FORCEPROP 1 LAST PACK_TYPE 0201LF
J 0
(-7710 4750);
DISPLAY 0.787234 (-7710 4750);
FORCEPROP 1 LAST VALUE 4.7K
J 0
(-7705 5000);
DISPLAY 0.787234 (-7705 5000);
FORCEPROP 1 LAST TOLERANCE 5%
J 0
(-7705 4950);
DISPLAY 0.787234 (-7705 4950);
FORCEPROP 1 LAST MATERIAL CHIP
J 0
(-7710 4850);
DISPLAY 0.787234 (-7710 4850);
FORCEPROP 1 LAST WATTAGE 1/20W
J 0
(-7710 4900);
DISPLAY 0.787234 (-7710 4900);
FORCEPROP 2 LAST CDS_LIB pure_quanta
J 0
(-7750 4925);
DISPLAY INVISIBLE (-7750 4925);
FORCEPROP 1 LAST PATH I37
J 0
(-7700 5100);
DISPLAY 0.978723 (-7700 5100);
PAINT WHITE (-7700 5100);
DISPLAY INVISIBLE (-7700 5100);
FORCEPROP 1 LAST PART_NUMBER CS24701JE04
J 0
(-7710 4800);
DISPLAY 0.787234 (-7710 4800);
DISPLAY INVISIBLE (-7710 4800);
FORCEADD UNIVERSAL_GND..1
(-7450 4450);
FORCEPROP 3 LASTPIN (-7450 4500) SIG_NAME GND\g
J 0
(-7440 4510);
DISPLAY 0.659574 (-7440 4510);
PAINT MONO (-7440 4510);
DISPLAY INVISIBLE (-7440 4510);
FORCEPROP 2 LAST CDS_LIB pure_quanta_power
J 0
(-7450 4450);
DISPLAY INVISIBLE (-7450 4450);
FORCEPROP 1 LAST HDL_POWER GND
J 1
(-7425 4375);
DISPLAY 0.872340 (-7425 4375);
PAINT GREEN (-7425 4375);
DISPLAY INVISIBLE (-7425 4375);
FORCEPROP 1 LAST PATH I38
J 0
(-7375 4450);
DISPLAY 0.872340 (-7375 4450);
PAINT AQUA (-7375 4450);
DISPLAY INVISIBLE (-7375 4450);
FORCEADD Q_RES..2
(-7450 4900);
FORCEPROP 1 LAST LOCATION R1079
J 0
(-7405 5025);
DISPLAY 0.787234 (-7405 5025);
FORCEPROP 0 LAST $SEC 1
J 0
(-7400 5075);
DISPLAY 0.680851 (-7400 5075);
PAINT MONO (-7400 5075);
DISPLAY INVISIBLE (-7400 5075);
FORCEPROP 0 LAST CDS_SEC 1
J 0
(-7400 5075);
DISPLAY 0.680851 (-7400 5075);
DISPLAY INVISIBLE (-7400 5075);
FORCEPROP 1 LASTPIN (-7450 5000) $PN 1
J 0
(-7445 4962);
DISPLAY 0.787234 (-7445 4962);
PAINT MONO (-7445 4962);
FORCEPROP 1 LASTPIN (-7450 4800) $PN 2
J 0
(-7445 4810);
DISPLAY 0.787234 (-7445 4810);
PAINT MONO (-7445 4810);
FORCEPROP 1 LAST TOLERANCE 5%
J 0
(-7405 4925);
DISPLAY 0.787234 (-7405 4925);
FORCEPROP 1 LAST VALUE 4.7K
J 0
(-7405 4975);
DISPLAY 0.787234 (-7405 4975);
FORCEPROP 1 LAST PACK_TYPE 0201LF
J 0
(-7410 4725);
DISPLAY 0.787234 (-7410 4725);
FORCEPROP 1 LAST MATERIAL CHIP
J 0
(-7410 4825);
DISPLAY 0.787234 (-7410 4825);
FORCEPROP 1 LAST WATTAGE 1/20W
J 0
(-7410 4875);
DISPLAY 0.787234 (-7410 4875);
FORCEPROP 2 LAST CDS_LIB pure_quanta
J 0
(-7450 4900);
DISPLAY INVISIBLE (-7450 4900);
FORCEPROP 1 LAST PATH I39
J 0
(-7400 5075);
DISPLAY 0.978723 (-7400 5075);
PAINT WHITE (-7400 5075);
DISPLAY INVISIBLE (-7400 5075);
FORCEPROP 1 LAST PART_NUMBER CS24701JE04
J 0
(-7410 4775);
DISPLAY 0.638298 (-7410 4775);
DISPLAY INVISIBLE (-7410 4775);
FORCEADD Q_RES..2
(-8050 5850);
FORCEPROP 1 LAST LOCATION R1075
J 0
(-8005 5975);
DISPLAY 0.787234 (-8005 5975);
FORCEPROP 0 LAST $SEC 1
J 0
(-8000 6025);
DISPLAY 0.680851 (-8000 6025);
PAINT MONO (-8000 6025);
DISPLAY INVISIBLE (-8000 6025);
FORCEPROP 0 LAST CDS_SEC 1
J 0
(-8000 6025);
DISPLAY 0.680851 (-8000 6025);
DISPLAY INVISIBLE (-8000 6025);
FORCEPROP 1 LASTPIN (-8050 5950) $PN 1
J 0
(-8045 5912);
DISPLAY 0.787234 (-8045 5912);
PAINT MONO (-8045 5912);
FORCEPROP 1 LASTPIN (-8050 5750) $PN 2
J 0
(-8045 5760);
DISPLAY 0.787234 (-8045 5760);
PAINT MONO (-8045 5760);
FORCEPROP 1 LAST TOLERANCE 5%
J 0
(-8005 5875);
DISPLAY 0.787234 (-8005 5875);
FORCEPROP 1 LAST VALUE 4.7K
J 0
(-8005 5925);
DISPLAY 0.787234 (-8005 5925);
FORCEPROP 1 LAST PACK_TYPE 0201LF
J 0
(-8000 5700);
DISPLAY 0.787234 (-8000 5700);
FORCEPROP 1 LAST MATERIAL EMPTY
J 0
(-8010 5775);
DISPLAY 0.787234 (-8010 5775);
FORCEPROP 1 LAST WATTAGE 1/20W
J 0
(-8010 5825);
DISPLAY 0.787234 (-8010 5825);
FORCEPROP 2 LAST CDS_LIB pure_quanta
J 0
(-8050 5850);
DISPLAY INVISIBLE (-8050 5850);
FORCEPROP 1 LAST PATH I40
J 0
(-8000 6025);
DISPLAY 0.978723 (-8000 6025);
PAINT WHITE (-8000 6025);
DISPLAY INVISIBLE (-8000 6025);
FORCEPROP 1 LAST PART_NUMBER CS24701JE04
J 0
(-8010 5725);
DISPLAY 0.978723 (-8010 5725);
DISPLAY INVISIBLE (-8010 5725);
FORCEADD Q_RES..2
(-7750 5875);
FORCEPROP 1 LAST LOCATION R1077
J 0
(-7705 6000);
DISPLAY 0.787234 (-7705 6000);
FORCEPROP 0 LAST $SEC 1
J 0
(-7700 6050);
DISPLAY 0.680851 (-7700 6050);
PAINT MONO (-7700 6050);
DISPLAY INVISIBLE (-7700 6050);
FORCEPROP 0 LAST CDS_SEC 1
J 0
(-7700 6050);
DISPLAY 0.680851 (-7700 6050);
DISPLAY INVISIBLE (-7700 6050);
FORCEPROP 1 LASTPIN (-7750 5975) $PN 1
J 0
(-7745 5937);
DISPLAY 0.787234 (-7745 5937);
PAINT MONO (-7745 5937);
FORCEPROP 1 LASTPIN (-7750 5775) $PN 2
J 0
(-7745 5785);
DISPLAY 0.787234 (-7745 5785);
PAINT MONO (-7745 5785);
FORCEPROP 1 LAST WATTAGE 1/20W
J 0
(-7710 5850);
DISPLAY 0.787234 (-7710 5850);
FORCEPROP 1 LAST MATERIAL EMPTY
J 0
(-7710 5800);
DISPLAY 0.787234 (-7710 5800);
FORCEPROP 1 LAST VALUE 4.7K
J 0
(-7705 5950);
DISPLAY 0.787234 (-7705 5950);
FORCEPROP 1 LAST TOLERANCE 5%
J 0
(-7705 5900);
DISPLAY 0.787234 (-7705 5900);
FORCEPROP 1 LAST PACK_TYPE 0201LF
J 0
(-7710 5700);
DISPLAY 0.787234 (-7710 5700);
FORCEPROP 2 LAST CDS_LIB pure_quanta
J 0
(-7750 5875);
DISPLAY INVISIBLE (-7750 5875);
FORCEPROP 1 LAST PATH I41
J 0
(-7700 6050);
DISPLAY 0.978723 (-7700 6050);
PAINT WHITE (-7700 6050);
DISPLAY INVISIBLE (-7700 6050);
FORCEPROP 1 LAST PART_NUMBER CS24701JE04
J 0
(-7710 5750);
DISPLAY 0.787234 (-7710 5750);
DISPLAY INVISIBLE (-7710 5750);
FORCEADD Q_RES..2
(-7450 5900);
FORCEPROP 1 LAST LOCATION R1066
J 0
(-7405 6025);
DISPLAY 0.787234 (-7405 6025);
FORCEPROP 0 LAST $SEC 1
J 0
(-7400 6075);
DISPLAY 0.680851 (-7400 6075);
PAINT MONO (-7400 6075);
DISPLAY INVISIBLE (-7400 6075);
FORCEPROP 0 LAST CDS_SEC 1
J 0
(-7400 6075);
DISPLAY 0.680851 (-7400 6075);
DISPLAY INVISIBLE (-7400 6075);
FORCEPROP 1 LASTPIN (-7450 6000) $PN 1
J 0
(-7445 5962);
DISPLAY 0.787234 (-7445 5962);
PAINT MONO (-7445 5962);
FORCEPROP 1 LASTPIN (-7450 5800) $PN 2
J 0
(-7445 5810);
DISPLAY 0.787234 (-7445 5810);
PAINT MONO (-7445 5810);
FORCEPROP 1 LAST MATERIAL EMPTY
J 0
(-7410 5825);
DISPLAY 0.787234 (-7410 5825);
FORCEPROP 1 LAST WATTAGE 1/20W
J 0
(-7410 5875);
DISPLAY 0.787234 (-7410 5875);
FORCEPROP 1 LAST VALUE 4.7K
J 0
(-7405 5975);
DISPLAY 0.787234 (-7405 5975);
FORCEPROP 1 LAST TOLERANCE 5%
J 0
(-7405 5925);
DISPLAY 0.787234 (-7405 5925);
FORCEPROP 1 LAST PACK_TYPE 0201LF
J 0
(-7400 5725);
DISPLAY 0.787234 (-7400 5725);
FORCEPROP 2 LAST CDS_LIB pure_quanta
J 0
(-7450 5900);
DISPLAY INVISIBLE (-7450 5900);
FORCEPROP 1 LAST PATH I42
J 0
(-7400 6075);
DISPLAY 0.978723 (-7400 6075);
PAINT WHITE (-7400 6075);
DISPLAY INVISIBLE (-7400 6075);
FORCEPROP 1 LAST PART_NUMBER CS24701JE04
J 0
(-7400 5775);
DISPLAY 0.638298 (-7400 5775);
DISPLAY INVISIBLE (-7400 5775);
FORCEADD OFFPAGE..5
R 2
(-6400 5300);
FORCEPROP 2 LAST $XR0 299 
J 0
(-6211 5300);
DISPLAY 0.638298 (-6211 5300);
PAINT MONO (-6211 5300);
FORCEPROP 2 LAST CDS_LIB standard
J 0
(-6400 5300);
DISPLAY INVISIBLE (-6400 5300);
FORCEPROP 1 LAST OFFPAGE TRUE
J 2
(-6725 5175);
DISPLAY 0.872340 (-6725 5175);
PAINT GREEN (-6725 5175);
DISPLAY INVISIBLE (-6725 5175);
FORCEPROP 1 LAST COMMENT_BODY TRUE
J 2
(-6500 5225);
DISPLAY 0.872340 (-6500 5225);
PAINT GREEN (-6500 5225);
DISPLAY INVISIBLE (-6500 5225);
FORCEPROP 2 LAST PATH I43
J 0
(-6200 5350);
DISPLAY 0.680851 (-6200 5350);
DISPLAY INVISIBLE (-6200 5350);
FORCEADD OFFPAGE..5
R 2
(-6400 5375);
FORCEPROP 2 LAST $XR0 299 
J 0
(-6211 5375);
DISPLAY 0.638298 (-6211 5375);
PAINT MONO (-6211 5375);
FORCEPROP 2 LAST CDS_LIB standard
J 0
(-6400 5375);
DISPLAY INVISIBLE (-6400 5375);
FORCEPROP 1 LAST OFFPAGE TRUE
J 2
(-6725 5250);
DISPLAY 0.872340 (-6725 5250);
PAINT GREEN (-6725 5250);
DISPLAY INVISIBLE (-6725 5250);
FORCEPROP 1 LAST COMMENT_BODY TRUE
J 2
(-6500 5300);
DISPLAY 0.872340 (-6500 5300);
PAINT GREEN (-6500 5300);
DISPLAY INVISIBLE (-6500 5300);
FORCEPROP 2 LAST PATH I44
J 0
(-6200 5425);
DISPLAY 0.680851 (-6200 5425);
DISPLAY INVISIBLE (-6200 5425);
FORCEADD OFFPAGE..5
R 2
(-6400 5425);
FORCEPROP 2 LAST $XR0 299 
J 0
(-6211 5425);
DISPLAY 0.638298 (-6211 5425);
PAINT MONO (-6211 5425);
FORCEPROP 2 LAST CDS_LIB standard
J 0
(-6400 5425);
DISPLAY INVISIBLE (-6400 5425);
FORCEPROP 1 LAST OFFPAGE TRUE
J 2
(-6725 5300);
DISPLAY 0.872340 (-6725 5300);
PAINT GREEN (-6725 5300);
DISPLAY INVISIBLE (-6725 5300);
FORCEPROP 1 LAST COMMENT_BODY TRUE
J 2
(-6500 5350);
DISPLAY 0.872340 (-6500 5350);
PAINT GREEN (-6500 5350);
DISPLAY INVISIBLE (-6500 5350);
FORCEPROP 2 LAST PATH I45
J 0
(-6200 5475);
DISPLAY 0.680851 (-6200 5475);
DISPLAY INVISIBLE (-6200 5475);
FORCEADD OFFPAGE..5
R 2
(-6400 5475);
FORCEPROP 2 LAST $XR0 299 
J 0
(-6211 5475);
DISPLAY 0.638298 (-6211 5475);
PAINT MONO (-6211 5475);
FORCEPROP 2 LAST CDS_LIB standard
J 0
(-6400 5475);
DISPLAY INVISIBLE (-6400 5475);
FORCEPROP 1 LAST OFFPAGE TRUE
J 2
(-6725 5350);
DISPLAY 0.872340 (-6725 5350);
PAINT GREEN (-6725 5350);
DISPLAY INVISIBLE (-6725 5350);
FORCEPROP 1 LAST COMMENT_BODY TRUE
J 2
(-6500 5400);
DISPLAY 0.872340 (-6500 5400);
PAINT GREEN (-6500 5400);
DISPLAY INVISIBLE (-6500 5400);
FORCEPROP 2 LAST PATH I46
J 0
(-6200 5525);
DISPLAY 0.680851 (-6200 5525);
DISPLAY INVISIBLE (-6200 5525);
FORCEADD OFFPAGE..5
R 2
(-6400 5525);
FORCEPROP 2 LAST $XR0 299 
J 0
(-6211 5525);
DISPLAY 0.638298 (-6211 5525);
PAINT MONO (-6211 5525);
FORCEPROP 2 LAST CDS_LIB standard
J 0
(-6400 5525);
DISPLAY INVISIBLE (-6400 5525);
FORCEPROP 1 LAST OFFPAGE TRUE
J 2
(-6725 5400);
DISPLAY 0.872340 (-6725 5400);
PAINT GREEN (-6725 5400);
DISPLAY INVISIBLE (-6725 5400);
FORCEPROP 1 LAST COMMENT_BODY TRUE
J 2
(-6500 5450);
DISPLAY 0.872340 (-6500 5450);
PAINT GREEN (-6500 5450);
DISPLAY INVISIBLE (-6500 5450);
FORCEPROP 2 LAST PATH I47
J 0
(-6200 5575);
DISPLAY 0.680851 (-6200 5575);
DISPLAY INVISIBLE (-6200 5575);
FORCEADD OFFPAGE..5
R 2
(-6400 5600);
FORCEPROP 2 LAST $XR0 299 
J 0
(-6211 5600);
DISPLAY 0.638298 (-6211 5600);
PAINT MONO (-6211 5600);
FORCEPROP 2 LAST CDS_LIB standard
J 0
(-6400 5600);
DISPLAY INVISIBLE (-6400 5600);
FORCEPROP 1 LAST OFFPAGE TRUE
J 2
(-6725 5475);
DISPLAY 0.872340 (-6725 5475);
PAINT GREEN (-6725 5475);
DISPLAY INVISIBLE (-6725 5475);
FORCEPROP 1 LAST COMMENT_BODY TRUE
J 2
(-6500 5525);
DISPLAY 0.872340 (-6500 5525);
PAINT GREEN (-6500 5525);
DISPLAY INVISIBLE (-6500 5525);
FORCEPROP 2 LAST PATH I48
J 0
(-6200 5650);
DISPLAY 0.680851 (-6200 5650);
DISPLAY INVISIBLE (-6200 5650);
FORCEADD UNIVERSAL_GND..1
(-5050 5100);
FORCEPROP 3 LASTPIN (-5050 5150) SIG_NAME GND\g
J 0
(-5040 5160);
DISPLAY 0.659574 (-5040 5160);
PAINT MONO (-5040 5160);
DISPLAY INVISIBLE (-5040 5160);
FORCEPROP 2 LAST CDS_LIB pure_quanta_power
J 0
(-5050 5100);
DISPLAY INVISIBLE (-5050 5100);
FORCEPROP 1 LAST HDL_POWER GND
J 1
(-5025 5025);
DISPLAY 0.872340 (-5025 5025);
PAINT GREEN (-5025 5025);
DISPLAY INVISIBLE (-5025 5025);
FORCEPROP 1 LAST PATH I49
J 0
(-4975 5100);
DISPLAY 0.872340 (-4975 5100);
PAINT AQUA (-4975 5100);
DISPLAY INVISIBLE (-4975 5100);
FORCEADD Q_RES..2
(-9000 4025);
FORCEPROP 1 LAST LOCATION R1063
J 0
(-8955 4150);
DISPLAY 0.787234 (-8955 4150);
FORCEPROP 0 LAST $SEC 1
J 0
(-8950 4200);
DISPLAY 0.680851 (-8950 4200);
PAINT MONO (-8950 4200);
DISPLAY INVISIBLE (-8950 4200);
FORCEPROP 0 LAST CDS_SEC 1
J 0
(-8950 4200);
DISPLAY 0.680851 (-8950 4200);
DISPLAY INVISIBLE (-8950 4200);
FORCEPROP 1 LASTPIN (-9000 4125) $PN 1
J 0
(-8995 4087);
DISPLAY 0.787234 (-8995 4087);
PAINT MONO (-8995 4087);
FORCEPROP 1 LASTPIN (-9000 3925) $PN 2
J 0
(-8995 3935);
DISPLAY 0.787234 (-8995 3935);
PAINT MONO (-8995 3935);
FORCEPROP 1 LAST MATERIAL EMPTY
J 0
(-8960 3950);
DISPLAY 0.787234 (-8960 3950);
FORCEPROP 1 LAST VALUE 4.7K
J 0
(-8955 4100);
DISPLAY 0.787234 (-8955 4100);
FORCEPROP 1 LAST TOLERANCE 5%
J 0
(-8955 4050);
DISPLAY 0.787234 (-8955 4050);
FORCEPROP 1 LAST WATTAGE 1/20W
J 0
(-8960 4000);
DISPLAY 0.787234 (-8960 4000);
FORCEPROP 1 LAST PACK_TYPE 0201LF
J 0
(-8950 3875);
DISPLAY 0.787234 (-8950 3875);
FORCEPROP 2 LAST CDS_LIB pure_quanta
J 0
(-9000 4025);
DISPLAY INVISIBLE (-9000 4025);
FORCEPROP 1 LAST PATH I5
J 0
(-8950 4200);
DISPLAY 0.978723 (-8950 4200);
PAINT WHITE (-8950 4200);
DISPLAY INVISIBLE (-8950 4200);
FORCEPROP 1 LAST PART_NUMBER CS24701JE04
J 0
(-8960 3900);
DISPLAY 0.978723 (-8960 3900);
DISPLAY INVISIBLE (-8960 3900);
FORCEADD Q_RES..2
(-5050 5450);
FORCEPROP 1 LAST LOCATION R1048
J 0
(-5005 5575);
DISPLAY 0.787234 (-5005 5575);
FORCEPROP 0 LAST $SEC 1
J 0
(-5000 5625);
DISPLAY 0.680851 (-5000 5625);
PAINT MONO (-5000 5625);
DISPLAY INVISIBLE (-5000 5625);
FORCEPROP 0 LAST CDS_SEC 1
J 0
(-5000 5625);
DISPLAY 0.680851 (-5000 5625);
DISPLAY INVISIBLE (-5000 5625);
FORCEPROP 1 LASTPIN (-5050 5550) $PN 1
J 0
(-5045 5512);
DISPLAY 0.787234 (-5045 5512);
PAINT MONO (-5045 5512);
FORCEPROP 1 LASTPIN (-5050 5350) $PN 2
J 0
(-5045 5360);
DISPLAY 0.787234 (-5045 5360);
PAINT MONO (-5045 5360);
FORCEPROP 1 LAST MATERIAL EMPTY
J 0
(-5010 5375);
DISPLAY 0.787234 (-5010 5375);
FORCEPROP 1 LAST WATTAGE 1/20W
J 0
(-5010 5425);
DISPLAY 0.787234 (-5010 5425);
FORCEPROP 1 LAST TOLERANCE 5%
J 0
(-5005 5475);
DISPLAY 0.787234 (-5005 5475);
FORCEPROP 1 LAST VALUE 4.7K
J 0
(-5005 5525);
DISPLAY 0.787234 (-5005 5525);
FORCEPROP 1 LAST PACK_TYPE 0201LF
J 0
(-5010 5275);
DISPLAY 0.787234 (-5010 5275);
FORCEPROP 2 LAST CDS_LIB pure_quanta
J 0
(-5050 5450);
DISPLAY INVISIBLE (-5050 5450);
FORCEPROP 1 LAST PATH I50
J 0
(-5000 5625);
DISPLAY 0.978723 (-5000 5625);
PAINT WHITE (-5000 5625);
DISPLAY INVISIBLE (-5000 5625);
FORCEPROP 1 LAST PART_NUMBER CS24701JE04
J 0
(-5010 5325);
DISPLAY 0.787234 (-5010 5325);
DISPLAY INVISIBLE (-5010 5325);
FORCEADD Q_RES..2
(-5050 5975);
FORCEPROP 1 LAST LOCATION R1080
J 0
(-5005 6100);
DISPLAY 0.787234 (-5005 6100);
FORCEPROP 0 LAST $SEC 1
J 0
(-5000 6150);
DISPLAY 0.680851 (-5000 6150);
PAINT MONO (-5000 6150);
DISPLAY INVISIBLE (-5000 6150);
FORCEPROP 0 LAST CDS_SEC 1
J 0
(-5000 6150);
DISPLAY 0.680851 (-5000 6150);
DISPLAY INVISIBLE (-5000 6150);
FORCEPROP 1 LASTPIN (-5050 6075) $PN 1
J 0
(-5045 6037);
DISPLAY 0.787234 (-5045 6037);
PAINT MONO (-5045 6037);
FORCEPROP 1 LASTPIN (-5050 5875) $PN 2
J 0
(-5045 5885);
DISPLAY 0.787234 (-5045 5885);
PAINT MONO (-5045 5885);
FORCEPROP 1 LAST PACK_TYPE 0201LF
J 0
(-5010 5800);
DISPLAY 0.787234 (-5010 5800);
FORCEPROP 1 LAST WATTAGE 1/20W
J 0
(-5010 5950);
DISPLAY 0.787234 (-5010 5950);
FORCEPROP 1 LAST TOLERANCE 5%
J 0
(-5005 6000);
DISPLAY 0.787234 (-5005 6000);
FORCEPROP 1 LAST MATERIAL CHIP
J 0
(-5010 5900);
DISPLAY 0.787234 (-5010 5900);
FORCEPROP 1 LAST VALUE 4.7K
J 0
(-5005 6050);
DISPLAY 0.787234 (-5005 6050);
FORCEPROP 2 LAST CDS_LIB pure_quanta
J 0
(-5050 5975);
DISPLAY INVISIBLE (-5050 5975);
FORCEPROP 1 LAST PATH I51
J 0
(-5000 6150);
DISPLAY 0.978723 (-5000 6150);
PAINT WHITE (-5000 6150);
DISPLAY INVISIBLE (-5000 6150);
FORCEPROP 1 LAST PART_NUMBER CS24701JE04
J 0
(-5010 5850);
DISPLAY 0.787234 (-5010 5850);
DISPLAY INVISIBLE (-5010 5850);
FORCEADD OFFPAGE..5
R 2
(-4175 5700);
FORCEPROP 2 LAST $XR0 299 
J 0
(-3986 5700);
DISPLAY 0.638298 (-3986 5700);
PAINT MONO (-3986 5700);
FORCEPROP 2 LAST CDS_LIB standard
J 0
(-4175 5700);
DISPLAY INVISIBLE (-4175 5700);
FORCEPROP 1 LAST OFFPAGE TRUE
J 2
(-4500 5575);
DISPLAY 0.872340 (-4500 5575);
PAINT GREEN (-4500 5575);
DISPLAY INVISIBLE (-4500 5575);
FORCEPROP 1 LAST COMMENT_BODY TRUE
J 2
(-4275 5625);
DISPLAY 0.872340 (-4275 5625);
PAINT GREEN (-4275 5625);
DISPLAY INVISIBLE (-4275 5625);
FORCEPROP 2 LAST PATH I52
J 0
(-3975 5750);
DISPLAY 0.680851 (-3975 5750);
DISPLAY INVISIBLE (-3975 5750);
FORCEADD P1V0..1
(-5050 6300);
FORCEPROP 3 LASTPIN (-5050 6250) SIG_NAME P1V8_CPU0_RT_1D\g
J 0
(-5040 6260);
DISPLAY 0.659574 (-5040 6260);
PAINT MONO (-5040 6260);
DISPLAY INVISIBLE (-5040 6260);
FORCEPROP 1 LAST HDL_POWER P1V8_CPU0_RT_1D
J 1
(-5050 6350);
DISPLAY 0.489362 (-5050 6350);
PAINT SKYBLUE (-5050 6350);
FORCEPROP 2 LAST CDS_LIB pure_quanta_power
J 0
(-5050 6300);
DISPLAY INVISIBLE (-5050 6300);
FORCEPROP 1 LAST PATH I53
J 0
(-5000 6325);
DISPLAY 0.872340 (-5000 6325);
PAINT AQUA (-5000 6325);
DISPLAY INVISIBLE (-5000 6325);
FORCEADD UNIVERSAL_GND..1
R 1
(-3075 1600);
FORCEPROP 3 LASTPIN (-3125 1600) SIG_NAME GND\g
J 0
(-3115 1610);
DISPLAY 0.659574 (-3115 1610);
PAINT MONO (-3115 1610);
DISPLAY INVISIBLE (-3115 1610);
FORCEPROP 2 LAST CDS_LIB pure_quanta_power
J 0
(-3075 1600);
DISPLAY INVISIBLE (-3075 1600);
FORCEPROP 1 LAST HDL_POWER GND
R 1
J 1
(-3000 1625);
DISPLAY 0.872340 (-3000 1625);
PAINT GREEN (-3000 1625);
DISPLAY INVISIBLE (-3000 1625);
FORCEPROP 1 LAST PATH I54
R 1
J 0
(-3075 1675);
DISPLAY 0.872340 (-3075 1675);
PAINT AQUA (-3075 1675);
DISPLAY INVISIBLE (-3075 1675);
FORCEADD Q_RES..1
(-2600 2000);
FORCEPROP 1 LAST LOCATION R1054
J 0
(-2875 2000);
DISPLAY 0.978723 (-2875 2000);
FORCEPROP 0 LAST $SEC 1
J 0
(-2300 2050);
DISPLAY 0.680851 (-2300 2050);
PAINT MONO (-2300 2050);
DISPLAY INVISIBLE (-2300 2050);
FORCEPROP 0 LAST CDS_SEC 1
J 0
(-2300 2050);
DISPLAY 0.680851 (-2300 2050);
DISPLAY INVISIBLE (-2300 2050);
FORCEPROP 1 LASTPIN (-2700 2000) $PN 1
J 0
(-2688 2012);
DISPLAY 0.787234 (-2688 2012);
PAINT MONO (-2688 2012);
FORCEPROP 1 LASTPIN (-2500 2000) $PN 2
J 0
(-2538 2012);
DISPLAY 0.787234 (-2538 2012);
PAINT MONO (-2538 2012);
FORCEPROP 1 LAST PACK_TYPE 0201LF
J 0
(-2300 2000);
DISPLAY 0.787234 (-2300 2000);
FORCEPROP 1 LAST VALUE 0
J 2
(-2400 2000);
DISPLAY 0.787234 (-2400 2000);
FORCEPROP 2 LAST CDS_LIB pure_quanta
J 0
(-2600 2000);
DISPLAY INVISIBLE (-2600 2000);
FORCEPROP 1 LAST MATERIAL CHIP
J 0
(-2775 2075);
DISPLAY 0.787234 (-2775 2075);
DISPLAY INVISIBLE (-2775 2075);
FORCEPROP 1 LAST TOLERANCE 5%
J 0
(-2775 2125);
DISPLAY 0.787234 (-2775 2125);
DISPLAY INVISIBLE (-2775 2125);
FORCEPROP 1 LAST WATTAGE 1/20W
J 2
(-2800 2075);
DISPLAY 0.787234 (-2800 2075);
DISPLAY INVISIBLE (-2800 2075);
FORCEPROP 1 LAST PATH I55
J 0
(-2650 2150);
DISPLAY 0.978723 (-2650 2150);
PAINT WHITE (-2650 2150);
DISPLAY INVISIBLE (-2650 2150);
FORCEPROP 1 LAST PART_NUMBER CS00001JE10
J 0
(-2650 2125);
DISPLAY 0.808511 (-2650 2125);
DISPLAY INVISIBLE (-2650 2125);
FORCEADD Q_RES..1
(-2600 2100);
FORCEPROP 1 LAST LOCATION R1047
J 0
(-2875 2100);
DISPLAY 0.978723 (-2875 2100);
FORCEPROP 2 LAST SEC 1
J 0
(-2650 2300);
DISPLAY 0.680851 (-2650 2300);
PAINT MONO (-2650 2300);
DISPLAY INVISIBLE (-2650 2300);
FORCEPROP 1 LASTPIN (-2700 2100) $PN 1
J 0
(-2688 2112);
DISPLAY 0.787234 (-2688 2112);
PAINT MONO (-2688 2112);
FORCEPROP 1 LASTPIN (-2500 2100) $PN 2
J 0
(-2538 2112);
DISPLAY 0.787234 (-2538 2112);
PAINT MONO (-2538 2112);
FORCEPROP 1 LAST VALUE 0
J 2
(-2400 2100);
DISPLAY 0.787234 (-2400 2100);
FORCEPROP 1 LAST PACK_TYPE 0201LF
J 0
(-2300 2100);
DISPLAY 0.787234 (-2300 2100);
FORCEPROP 1 LAST WATTAGE 1/20W
J 2
(-2800 2175);
DISPLAY 0.787234 (-2800 2175);
DISPLAY INVISIBLE (-2800 2175);
FORCEPROP 1 LAST TOLERANCE 5%
J 0
(-2775 2225);
DISPLAY 0.787234 (-2775 2225);
DISPLAY INVISIBLE (-2775 2225);
FORCEPROP 1 LAST MATERIAL CHIP
J 0
(-2775 2175);
DISPLAY 0.787234 (-2775 2175);
DISPLAY INVISIBLE (-2775 2175);
FORCEPROP 2 LAST SEC_TYPE 0201LF
J 0
(-2650 2300);
DISPLAY 0.680851 (-2650 2300);
DISPLAY INVISIBLE (-2650 2300);
FORCEPROP 2 LAST CDS_LIB pure_quanta
J 0
(-2600 2100);
DISPLAY INVISIBLE (-2600 2100);
FORCEPROP 1 LAST PATH I56
J 0
(-2650 2250);
DISPLAY 0.978723 (-2650 2250);
PAINT WHITE (-2650 2250);
DISPLAY INVISIBLE (-2650 2250);
FORCEPROP 1 LAST PART_NUMBER CS00001JE10
J 0
(-2650 2225);
DISPLAY 0.808511 (-2650 2225);
DISPLAY INVISIBLE (-2650 2225);
FORCEADD OFFPAGE..1
R 2
(-2425 2700);
FORCEPROP 2 LAST $XR0 299 
J 0
(-2239 2700);
DISPLAY 0.638298 (-2239 2700);
PAINT MONO (-2239 2700);
FORCEPROP 2 LAST CDS_LIB standard
J 2
(-2425 2700);
DISPLAY INVISIBLE (-2425 2700);
FORCEPROP 1 LAST OFFPAGE TRUE
J 2
(-2750 2575);
DISPLAY 0.872340 (-2750 2575);
DISPLAY INVISIBLE (-2750 2575);
FORCEPROP 1 LAST COMMENT_BODY TRUE
J 2
(-2550 2600);
DISPLAY 0.872340 (-2550 2600);
PAINT GREEN (-2550 2600);
DISPLAY INVISIBLE (-2550 2600);
FORCEPROP 2 LAST PATH I58
J 0
(-2225 2750);
DISPLAY 0.680851 (-2225 2750);
DISPLAY INVISIBLE (-2225 2750);
FORCEADD OFFPAGE..1
R 2
(-2400 2500);
FORCEPROP 2 LAST $XR0 299 
J 0
(-2214 2500);
DISPLAY 0.638298 (-2214 2500);
PAINT MONO (-2214 2500);
FORCEPROP 2 LAST CDS_LIB standard
J 0
(-2400 2500);
DISPLAY INVISIBLE (-2400 2500);
FORCEPROP 1 LAST OFFPAGE TRUE
J 2
(-2725 2375);
DISPLAY 0.872340 (-2725 2375);
DISPLAY INVISIBLE (-2725 2375);
FORCEPROP 1 LAST COMMENT_BODY TRUE
J 2
(-2525 2400);
DISPLAY 0.872340 (-2525 2400);
PAINT GREEN (-2525 2400);
DISPLAY INVISIBLE (-2525 2400);
FORCEPROP 2 LAST PATH I59
J 0
(-2200 2550);
DISPLAY 0.680851 (-2200 2550);
DISPLAY INVISIBLE (-2200 2550);
FORCEADD P1V0..1
(-9000 4350);
FORCEPROP 3 LASTPIN (-9000 4300) SIG_NAME P1V8_CPU0_RT_1D\g
J 0
(-8990 4310);
DISPLAY 0.659574 (-8990 4310);
PAINT MONO (-8990 4310);
DISPLAY INVISIBLE (-8990 4310);
FORCEPROP 1 LAST HDL_POWER P1V8_CPU0_RT_1D
J 1
(-9000 4400);
DISPLAY 0.489362 (-9000 4400);
PAINT SKYBLUE (-9000 4400);
FORCEPROP 2 LAST CDS_LIB pure_quanta_power
J 0
(-9000 4350);
DISPLAY INVISIBLE (-9000 4350);
FORCEPROP 1 LAST PATH I6
J 0
(-8950 4375);
DISPLAY 0.872340 (-8950 4375);
PAINT AQUA (-8950 4375);
DISPLAY INVISIBLE (-8950 4375);
FORCEADD OFFPAGE..1
R 2
(-2500 3000);
FORCEPROP 2 LAST $XR0 299 
J 0
(-2314 3000);
DISPLAY 0.638298 (-2314 3000);
PAINT MONO (-2314 3000);
FORCEPROP 2 LAST CDS_LIB standard
J 0
(-2500 3000);
DISPLAY INVISIBLE (-2500 3000);
FORCEPROP 1 LAST OFFPAGE TRUE
J 2
(-2825 2875);
DISPLAY 0.872340 (-2825 2875);
DISPLAY INVISIBLE (-2825 2875);
FORCEPROP 1 LAST COMMENT_BODY TRUE
J 2
(-2625 2900);
DISPLAY 0.872340 (-2625 2900);
PAINT GREEN (-2625 2900);
DISPLAY INVISIBLE (-2625 2900);
FORCEPROP 2 LAST PATH I60
J 0
(-2300 3050);
DISPLAY 0.680851 (-2300 3050);
DISPLAY INVISIBLE (-2300 3050);
FORCEADD OFFPAGE..1
R 2
(-1075 2000);
FORCEPROP 2 LAST $XR1 299 
J 0
(-799 2000);
DISPLAY 0.638298 (-799 2000);
PAINT MONO (-799 2000);
FORCEPROP 2 LAST $XR0 81 
J 0
(-889 2000);
DISPLAY 0.638298 (-889 2000);
PAINT MONO (-889 2000);
FORCEPROP 2 LAST CDS_LIB standard
J 0
(-1075 2000);
DISPLAY INVISIBLE (-1075 2000);
FORCEPROP 1 LAST OFFPAGE TRUE
J 2
(-1400 1875);
DISPLAY 0.872340 (-1400 1875);
DISPLAY INVISIBLE (-1400 1875);
FORCEPROP 1 LAST COMMENT_BODY TRUE
J 2
(-1200 1900);
DISPLAY 0.872340 (-1200 1900);
PAINT GREEN (-1200 1900);
DISPLAY INVISIBLE (-1200 1900);
FORCEPROP 2 LAST PATH I62
J 0
(-775 2050);
DISPLAY 0.680851 (-775 2050);
DISPLAY INVISIBLE (-775 2050);
FORCEADD OFFPAGE..1
R 2
(-1075 2100);
FORCEPROP 2 LAST $XR1 299 
J 0
(-799 2100);
DISPLAY 0.638298 (-799 2100);
PAINT MONO (-799 2100);
FORCEPROP 2 LAST $XR0 81 
J 0
(-889 2100);
DISPLAY 0.638298 (-889 2100);
PAINT MONO (-889 2100);
FORCEPROP 2 LAST CDS_LIB standard
J 0
(-1075 2100);
DISPLAY INVISIBLE (-1075 2100);
FORCEPROP 1 LAST OFFPAGE TRUE
J 2
(-1400 1975);
DISPLAY 0.872340 (-1400 1975);
DISPLAY INVISIBLE (-1400 1975);
FORCEPROP 1 LAST COMMENT_BODY TRUE
J 2
(-1200 2000);
DISPLAY 0.872340 (-1200 2000);
PAINT GREEN (-1200 2000);
DISPLAY INVISIBLE (-1200 2000);
FORCEPROP 2 LAST PATH I63
J 0
(-775 2150);
DISPLAY 0.680851 (-775 2150);
DISPLAY INVISIBLE (-775 2150);
FORCEADD UNIVERSAL_GND..1
(-3500 4700);
FORCEPROP 3 LASTPIN (-3500 4750) SIG_NAME GND\g
J 0
(-3490 4760);
DISPLAY 0.659574 (-3490 4760);
PAINT MONO (-3490 4760);
DISPLAY INVISIBLE (-3490 4760);
FORCEPROP 2 LAST CDS_LIB pure_quanta_power
J 0
(-3500 4700);
DISPLAY INVISIBLE (-3500 4700);
FORCEPROP 1 LAST HDL_POWER GND
J 1
(-3475 4625);
DISPLAY 0.872340 (-3475 4625);
PAINT GREEN (-3475 4625);
DISPLAY INVISIBLE (-3475 4625);
FORCEPROP 1 LAST PATH I64
J 0
(-3425 4700);
DISPLAY 0.872340 (-3425 4700);
PAINT AQUA (-3425 4700);
DISPLAY INVISIBLE (-3425 4700);
FORCEADD Q_RES..2
(-3500 5125);
FORCEPROP 1 LAST LOCATION R1056
J 0
(-3455 5250);
DISPLAY 0.787234 (-3455 5250);
FORCEPROP 0 LAST $SEC 1
J 0
(-3450 5300);
DISPLAY 0.680851 (-3450 5300);
PAINT MONO (-3450 5300);
DISPLAY INVISIBLE (-3450 5300);
FORCEPROP 0 LAST CDS_SEC 1
J 0
(-3450 5300);
DISPLAY 0.680851 (-3450 5300);
DISPLAY INVISIBLE (-3450 5300);
FORCEPROP 1 LASTPIN (-3500 5225) $PN 1
J 0
(-3495 5187);
DISPLAY 0.787234 (-3495 5187);
PAINT MONO (-3495 5187);
FORCEPROP 1 LASTPIN (-3500 5025) $PN 2
J 0
(-3495 5035);
DISPLAY 0.787234 (-3495 5035);
PAINT MONO (-3495 5035);
FORCEPROP 1 LAST PACK_TYPE 0201LF
J 0
(-3460 4950);
DISPLAY 0.787234 (-3460 4950);
FORCEPROP 1 LAST VALUE 1K
J 0
(-3455 5200);
DISPLAY 0.787234 (-3455 5200);
FORCEPROP 1 LAST MATERIAL EMPTY
J 0
(-3460 5050);
DISPLAY 0.787234 (-3460 5050);
FORCEPROP 1 LAST TOLERANCE 1%
J 0
(-3455 5150);
DISPLAY 0.787234 (-3455 5150);
FORCEPROP 1 LAST WATTAGE 1/20W
J 0
(-3460 5100);
DISPLAY 0.787234 (-3460 5100);
FORCEPROP 2 LAST CDS_LIB pure_quanta
J 0
(-3500 5125);
DISPLAY INVISIBLE (-3500 5125);
FORCEPROP 1 LAST PATH I65
J 0
(-3450 5300);
DISPLAY 0.978723 (-3450 5300);
PAINT WHITE (-3450 5300);
DISPLAY INVISIBLE (-3450 5300);
FORCEPROP 1 LAST PART_NUMBER CS21001FE07
J 0
(-3460 5000);
DISPLAY 0.978723 (-3460 5000);
DISPLAY INVISIBLE (-3460 5000);
FORCEADD Q_RES..2
(-3200 5125);
FORCEPROP 1 LAST LOCATION R1058
J 0
(-3155 5250);
DISPLAY 0.787234 (-3155 5250);
FORCEPROP 0 LAST $SEC 1
J 0
(-3150 5300);
DISPLAY 0.680851 (-3150 5300);
PAINT MONO (-3150 5300);
DISPLAY INVISIBLE (-3150 5300);
FORCEPROP 0 LAST CDS_SEC 1
J 0
(-3150 5300);
DISPLAY 0.680851 (-3150 5300);
DISPLAY INVISIBLE (-3150 5300);
FORCEPROP 1 LASTPIN (-3200 5225) $PN 1
J 0
(-3195 5187);
DISPLAY 0.787234 (-3195 5187);
PAINT MONO (-3195 5187);
FORCEPROP 1 LASTPIN (-3200 5025) $PN 2
J 0
(-3195 5035);
DISPLAY 0.787234 (-3195 5035);
PAINT MONO (-3195 5035);
FORCEPROP 1 LAST VALUE 20K
J 0
(-3155 5200);
DISPLAY 0.787234 (-3155 5200);
FORCEPROP 1 LAST TOLERANCE 1%
J 0
(-3155 5150);
DISPLAY 0.787234 (-3155 5150);
FORCEPROP 1 LAST WATTAGE 1/20W
J 0
(-3160 5100);
DISPLAY 0.787234 (-3160 5100);
FORCEPROP 1 LAST MATERIAL CHIP
J 0
(-3160 5050);
DISPLAY 0.787234 (-3160 5050);
FORCEPROP 1 LAST PACK_TYPE 0201LF
J 0
(-3160 4950);
DISPLAY 0.787234 (-3160 4950);
FORCEPROP 2 LAST CDS_LIB pure_quanta
J 0
(-3200 5125);
DISPLAY INVISIBLE (-3200 5125);
FORCEPROP 1 LAST PATH I66
J 0
(-3150 5300);
DISPLAY 0.978723 (-3150 5300);
PAINT WHITE (-3150 5300);
DISPLAY INVISIBLE (-3150 5300);
FORCEPROP 1 LAST PART_NUMBER CS32001FE00
J 0
(-3160 5000);
DISPLAY 0.978723 (-3160 5000);
DISPLAY INVISIBLE (-3160 5000);
FORCEADD Q_RES..2
(-3500 5900);
FORCEPROP 1 LAST LOCATION R1055
J 0
(-3455 6025);
DISPLAY 0.787234 (-3455 6025);
FORCEPROP 0 LAST $SEC 1
J 0
(-3450 6075);
DISPLAY 0.680851 (-3450 6075);
PAINT MONO (-3450 6075);
DISPLAY INVISIBLE (-3450 6075);
FORCEPROP 0 LAST CDS_SEC 1
J 0
(-3450 6075);
DISPLAY 0.680851 (-3450 6075);
DISPLAY INVISIBLE (-3450 6075);
FORCEPROP 1 LASTPIN (-3500 6000) $PN 1
J 0
(-3495 5962);
DISPLAY 0.787234 (-3495 5962);
PAINT MONO (-3495 5962);
FORCEPROP 1 LASTPIN (-3500 5800) $PN 2
J 0
(-3495 5810);
DISPLAY 0.787234 (-3495 5810);
PAINT MONO (-3495 5810);
FORCEPROP 1 LAST PACK_TYPE 0201LF
J 0
(-3460 5725);
DISPLAY 0.787234 (-3460 5725);
FORCEPROP 1 LAST TOLERANCE 1%
J 0
(-3455 5925);
DISPLAY 0.787234 (-3455 5925);
FORCEPROP 1 LAST VALUE 1K
J 0
(-3455 5975);
DISPLAY 0.787234 (-3455 5975);
FORCEPROP 1 LAST MATERIAL CHIP
J 0
(-3460 5825);
DISPLAY 0.787234 (-3460 5825);
FORCEPROP 1 LAST WATTAGE 1/20W
J 0
(-3460 5875);
DISPLAY 0.787234 (-3460 5875);
FORCEPROP 2 LAST CDS_LIB pure_quanta
J 0
(-3500 5900);
DISPLAY INVISIBLE (-3500 5900);
FORCEPROP 1 LAST PATH I67
J 0
(-3450 6075);
DISPLAY 0.978723 (-3450 6075);
PAINT WHITE (-3450 6075);
DISPLAY INVISIBLE (-3450 6075);
FORCEPROP 1 LAST PART_NUMBER CS21001FE07
J 0
(-3460 5775);
DISPLAY 0.978723 (-3460 5775);
DISPLAY INVISIBLE (-3460 5775);
FORCEADD Q_RES..2
(-3200 5900);
FORCEPROP 1 LAST LOCATION R1057
J 0
(-3155 6025);
DISPLAY 0.978723 (-3155 6025);
FORCEPROP 0 LAST $SEC 1
J 0
(-3150 6075);
DISPLAY 0.680851 (-3150 6075);
PAINT MONO (-3150 6075);
DISPLAY INVISIBLE (-3150 6075);
FORCEPROP 0 LAST CDS_SEC 1
J 0
(-3150 6075);
DISPLAY 0.680851 (-3150 6075);
DISPLAY INVISIBLE (-3150 6075);
FORCEPROP 1 LASTPIN (-3200 6000) $PN 1
J 0
(-3195 5962);
DISPLAY 0.787234 (-3195 5962);
PAINT MONO (-3195 5962);
FORCEPROP 1 LASTPIN (-3200 5800) $PN 2
J 0
(-3195 5810);
DISPLAY 0.787234 (-3195 5810);
PAINT MONO (-3195 5810);
FORCEPROP 1 LAST TOLERANCE 1%
J 0
(-3155 5925);
DISPLAY 0.787234 (-3155 5925);
FORCEPROP 1 LAST VALUE 1K
J 0
(-3155 5975);
DISPLAY 0.787234 (-3155 5975);
FORCEPROP 1 LAST WATTAGE 1/20W
J 0
(-3160 5875);
DISPLAY 0.787234 (-3160 5875);
FORCEPROP 1 LAST MATERIAL EMPTY
J 0
(-3160 5825);
DISPLAY 0.787234 (-3160 5825);
FORCEPROP 1 LAST PACK_TYPE 0201LF
J 0
(-3160 5725);
DISPLAY 0.787234 (-3160 5725);
FORCEPROP 2 LAST CDS_LIB pure_quanta
J 0
(-3200 5900);
DISPLAY INVISIBLE (-3200 5900);
FORCEPROP 1 LAST PATH I68
J 0
(-3150 6075);
DISPLAY 0.978723 (-3150 6075);
PAINT WHITE (-3150 6075);
DISPLAY INVISIBLE (-3150 6075);
FORCEPROP 1 LAST PART_NUMBER CS21001FE07
J 0
(-3160 5775);
DISPLAY 0.978723 (-3160 5775);
DISPLAY INVISIBLE (-3160 5775);
FORCEADD Q_RES..2
(-2850 5125);
FORCEPROP 1 LAST LOCATION R1060
J 0
(-2805 5250);
DISPLAY 0.978723 (-2805 5250);
FORCEPROP 0 LAST $SEC 1
J 0
(-2800 5300);
DISPLAY 0.680851 (-2800 5300);
PAINT MONO (-2800 5300);
DISPLAY INVISIBLE (-2800 5300);
FORCEPROP 0 LAST CDS_SEC 1
J 0
(-2800 5300);
DISPLAY 0.680851 (-2800 5300);
DISPLAY INVISIBLE (-2800 5300);
FORCEPROP 1 LASTPIN (-2850 5225) $PN 1
J 0
(-2845 5187);
DISPLAY 0.787234 (-2845 5187);
PAINT MONO (-2845 5187);
FORCEPROP 1 LASTPIN (-2850 5025) $PN 2
J 0
(-2845 5035);
DISPLAY 0.787234 (-2845 5035);
PAINT MONO (-2845 5035);
FORCEPROP 1 LAST PACK_TYPE 0201LF
J 0
(-2810 4950);
DISPLAY 0.787234 (-2810 4950);
FORCEPROP 1 LAST VALUE 1K
J 0
(-2805 5200);
DISPLAY 0.787234 (-2805 5200);
FORCEPROP 1 LAST TOLERANCE 1%
J 0
(-2805 5150);
DISPLAY 0.787234 (-2805 5150);
FORCEPROP 1 LAST WATTAGE 1/20W
J 0
(-2810 5100);
DISPLAY 0.787234 (-2810 5100);
FORCEPROP 1 LAST MATERIAL CHIP
J 0
(-2810 5050);
DISPLAY 0.787234 (-2810 5050);
FORCEPROP 2 LAST CDS_LIB pure_quanta
J 0
(-2850 5125);
DISPLAY INVISIBLE (-2850 5125);
FORCEPROP 1 LAST PATH I69
J 0
(-2800 5300);
DISPLAY 0.978723 (-2800 5300);
PAINT WHITE (-2800 5300);
DISPLAY INVISIBLE (-2800 5300);
FORCEPROP 1 LAST PART_NUMBER CS21001FE07
J 0
(-2810 5000);
DISPLAY 0.978723 (-2810 5000);
DISPLAY INVISIBLE (-2810 5000);
FORCEADD Q_RES..2
(-8975 4950);
FORCEPROP 1 LAST LOCATION R1070
J 0
(-8930 5075);
DISPLAY 0.787234 (-8930 5075);
FORCEPROP 0 LAST $SEC 1
J 0
(-8925 5125);
DISPLAY 0.680851 (-8925 5125);
PAINT MONO (-8925 5125);
DISPLAY INVISIBLE (-8925 5125);
FORCEPROP 0 LAST CDS_SEC 1
J 0
(-8925 5125);
DISPLAY 0.680851 (-8925 5125);
DISPLAY INVISIBLE (-8925 5125);
FORCEPROP 1 LASTPIN (-8975 5050) $PN 1
J 0
(-8970 5012);
DISPLAY 0.787234 (-8970 5012);
PAINT MONO (-8970 5012);
FORCEPROP 1 LASTPIN (-8975 4850) $PN 2
J 0
(-8970 4860);
DISPLAY 0.787234 (-8970 4860);
PAINT MONO (-8970 4860);
FORCEPROP 1 LAST VALUE 10K
J 0
(-8930 5025);
DISPLAY 0.787234 (-8930 5025);
FORCEPROP 1 LAST TOLERANCE 1%
J 0
(-8930 4975);
DISPLAY 0.787234 (-8930 4975);
FORCEPROP 1 LAST WATTAGE 1/20W
J 0
(-8935 4925);
DISPLAY 0.787234 (-8935 4925);
FORCEPROP 1 LAST MATERIAL CHIP
J 0
(-8935 4875);
DISPLAY 0.787234 (-8935 4875);
FORCEPROP 1 LAST PACK_TYPE 0201LF
J 0
(-8935 4775);
DISPLAY 0.787234 (-8935 4775);
FORCEPROP 2 LAST CDS_LIB pure_quanta
J 0
(-8975 4950);
DISPLAY INVISIBLE (-8975 4950);
FORCEPROP 1 LAST PATH I7
J 0
(-8925 5125);
DISPLAY 0.978723 (-8925 5125);
PAINT WHITE (-8925 5125);
DISPLAY INVISIBLE (-8925 5125);
FORCEPROP 1 LAST PART_NUMBER CS31001FE17
J 0
(-8935 4825);
DISPLAY 0.638298 (-8935 4825);
DISPLAY INVISIBLE (-8935 4825);
FORCEADD Q_RES..2
(-2850 5875);
FORCEPROP 1 LAST LOCATION R1059
J 0
(-2805 6000);
DISPLAY 0.978723 (-2805 6000);
FORCEPROP 0 LAST $SEC 1
J 0
(-2800 6050);
DISPLAY 0.680851 (-2800 6050);
PAINT MONO (-2800 6050);
DISPLAY INVISIBLE (-2800 6050);
FORCEPROP 0 LAST CDS_SEC 1
J 0
(-2800 6050);
DISPLAY 0.680851 (-2800 6050);
DISPLAY INVISIBLE (-2800 6050);
FORCEPROP 1 LASTPIN (-2850 5975) $PN 1
J 0
(-2845 5937);
DISPLAY 0.787234 (-2845 5937);
PAINT MONO (-2845 5937);
FORCEPROP 1 LASTPIN (-2850 5775) $PN 2
J 0
(-2845 5785);
DISPLAY 0.787234 (-2845 5785);
PAINT MONO (-2845 5785);
FORCEPROP 1 LAST WATTAGE 1/20W
J 0
(-2810 5850);
DISPLAY 0.787234 (-2810 5850);
FORCEPROP 1 LAST TOLERANCE 1%
J 0
(-2805 5900);
DISPLAY 0.787234 (-2805 5900);
FORCEPROP 1 LAST VALUE 1K
J 0
(-2805 5950);
DISPLAY 0.787234 (-2805 5950);
FORCEPROP 1 LAST PACK_TYPE 0201LF
J 0
(-2810 5700);
DISPLAY 0.787234 (-2810 5700);
FORCEPROP 1 LAST MATERIAL EMPTY
J 0
(-2810 5800);
DISPLAY 0.787234 (-2810 5800);
FORCEPROP 2 LAST CDS_LIB pure_quanta
J 0
(-2850 5875);
DISPLAY INVISIBLE (-2850 5875);
FORCEPROP 1 LAST PATH I70
J 0
(-2800 6050);
DISPLAY 0.978723 (-2800 6050);
PAINT WHITE (-2800 6050);
DISPLAY INVISIBLE (-2800 6050);
FORCEPROP 1 LAST PART_NUMBER CS21001FE07
J 0
(-2810 5750);
DISPLAY 0.978723 (-2810 5750);
DISPLAY INVISIBLE (-2810 5750);
FORCEADD P1V0..1
(-3500 6325);
FORCEPROP 3 LASTPIN (-3500 6275) SIG_NAME P1V8_CPU0_RT_1D\g
J 0
(-3490 6285);
DISPLAY 0.659574 (-3490 6285);
PAINT MONO (-3490 6285);
DISPLAY INVISIBLE (-3490 6285);
FORCEPROP 1 LAST HDL_POWER P1V8_CPU0_RT_1D
J 1
(-3500 6375);
DISPLAY 0.489362 (-3500 6375);
PAINT SKYBLUE (-3500 6375);
FORCEPROP 2 LAST CDS_LIB pure_quanta_power
J 0
(-3500 6325);
DISPLAY INVISIBLE (-3500 6325);
FORCEPROP 1 LAST PATH I71
J 0
(-3450 6350);
DISPLAY 0.872340 (-3450 6350);
PAINT AQUA (-3450 6350);
DISPLAY INVISIBLE (-3450 6350);
FORCEADD GND..1
(-1500 4750);
FORCEPROP 3 LASTPIN (-1500 4800) SIG_NAME GND\g
J 0
(-1490 4810);
DISPLAY 0.659574 (-1490 4810);
PAINT MONO (-1490 4810);
DISPLAY INVISIBLE (-1490 4810);
FORCEPROP 2 LAST CDS_LIB pure_quanta_power
J 0
(-1500 4750);
DISPLAY INVISIBLE (-1500 4750);
FORCEPROP 1 LAST SIZE 1B
J 0
(-1425 4700);
DISPLAY 0.851064 (-1425 4700);
PAINT GREEN (-1425 4700);
DISPLAY INVISIBLE (-1425 4700);
FORCEPROP 2 LAST BOM_COST MEM
J 0
(-1600 4825);
DISPLAY 0.808511 (-1600 4825);
DISPLAY INVISIBLE (-1600 4825);
FORCEPROP 1 LAST HDL_POWER GND
J 0
(-1500 4900);
DISPLAY 0.851064 (-1500 4900);
PAINT GREEN (-1500 4900);
DISPLAY INVISIBLE (-1500 4900);
FORCEPROP 1 LAST PATH I72
J 0
(-1425 4750);
DISPLAY 0.872340 (-1425 4750);
PAINT AQUA (-1425 4750);
DISPLAY INVISIBLE (-1425 4750);
FORCEADD GND..1
(-1325 4775);
FORCEPROP 3 LASTPIN (-1325 4825) SIG_NAME GND\g
J 0
(-1315 4835);
DISPLAY 0.659574 (-1315 4835);
PAINT MONO (-1315 4835);
DISPLAY INVISIBLE (-1315 4835);
FORCEPROP 1 LAST SIZE 1B
J 0
(-1250 4725);
DISPLAY 0.851064 (-1250 4725);
PAINT GREEN (-1250 4725);
DISPLAY INVISIBLE (-1250 4725);
FORCEPROP 2 LAST BOM_COST MEM
J 0
(-1425 4850);
DISPLAY 0.808511 (-1425 4850);
DISPLAY INVISIBLE (-1425 4850);
FORCEPROP 2 LAST CDS_LIB pure_quanta_power
J 0
(-1325 4775);
DISPLAY INVISIBLE (-1325 4775);
FORCEPROP 1 LAST HDL_POWER GND
J 0
(-1325 4925);
DISPLAY 0.851064 (-1325 4925);
PAINT GREEN (-1325 4925);
DISPLAY INVISIBLE (-1325 4925);
FORCEPROP 1 LAST PATH I73
J 0
(-1250 4775);
DISPLAY 0.872340 (-1250 4775);
PAINT AQUA (-1250 4775);
DISPLAY INVISIBLE (-1250 4775);
FORCEADD OFFPAGE..5
R 2
(-1950 5475);
FORCEPROP 2 LAST $XR0 299 
J 0
(-1761 5475);
DISPLAY 0.638298 (-1761 5475);
PAINT MONO (-1761 5475);
FORCEPROP 2 LAST CDS_LIB standard
J 0
(-1950 5475);
DISPLAY INVISIBLE (-1950 5475);
FORCEPROP 1 LAST OFFPAGE TRUE
J 2
(-2275 5350);
DISPLAY 0.872340 (-2275 5350);
PAINT GREEN (-2275 5350);
DISPLAY INVISIBLE (-2275 5350);
FORCEPROP 1 LAST COMMENT_BODY TRUE
J 2
(-2050 5400);
DISPLAY 0.872340 (-2050 5400);
PAINT GREEN (-2050 5400);
DISPLAY INVISIBLE (-2050 5400);
FORCEPROP 2 LAST PATH I74
J 0
(-1750 5525);
DISPLAY 0.680851 (-1750 5525);
DISPLAY INVISIBLE (-1750 5525);
FORCEADD OFFPAGE..5
R 2
(-1950 5575);
FORCEPROP 2 LAST $XR0 299 
J 0
(-1761 5575);
DISPLAY 0.638298 (-1761 5575);
PAINT MONO (-1761 5575);
FORCEPROP 2 LAST CDS_LIB standard
J 0
(-1950 5575);
DISPLAY INVISIBLE (-1950 5575);
FORCEPROP 1 LAST OFFPAGE TRUE
J 2
(-2275 5450);
DISPLAY 0.872340 (-2275 5450);
PAINT GREEN (-2275 5450);
DISPLAY INVISIBLE (-2275 5450);
FORCEPROP 1 LAST COMMENT_BODY TRUE
J 2
(-2050 5500);
DISPLAY 0.872340 (-2050 5500);
PAINT GREEN (-2050 5500);
DISPLAY INVISIBLE (-2050 5500);
FORCEPROP 2 LAST PATH I75
J 0
(-1750 5625);
DISPLAY 0.680851 (-1750 5625);
DISPLAY INVISIBLE (-1750 5625);
FORCEADD Q_RES..2
R 2
(-1500 5125);
FORCEPROP 1 LAST LOCATION R1062
J 2
(-1545 5250);
DISPLAY 0.638298 (-1545 5250);
FORCEPROP 0 LAST $SEC 1
J 0
(-1525 5300);
DISPLAY 0.680851 (-1525 5300);
PAINT MONO (-1525 5300);
DISPLAY INVISIBLE (-1525 5300);
FORCEPROP 0 LAST CDS_SEC 1
J 0
(-1525 5300);
DISPLAY 0.680851 (-1525 5300);
DISPLAY INVISIBLE (-1525 5300);
FORCEPROP 1 LASTPIN (-1500 5225) $PN 1
J 2
(-1505 5187);
DISPLAY 0.787234 (-1505 5187);
PAINT MONO (-1505 5187);
FORCEPROP 1 LASTPIN (-1500 5025) $PN 2
J 2
(-1505 5035);
DISPLAY 0.787234 (-1505 5035);
PAINT MONO (-1505 5035);
FORCEPROP 1 LAST TOLERANCE 1%
J 2
(-1545 5150);
DISPLAY 0.638298 (-1545 5150);
FORCEPROP 1 LAST WATTAGE 1/20W
J 2
(-1540 5100);
DISPLAY 0.638298 (-1540 5100);
FORCEPROP 1 LAST VALUE 10K
J 2
(-1545 5200);
DISPLAY 0.638298 (-1545 5200);
FORCEPROP 1 LAST MATERIAL CHIP
J 2
(-1540 5050);
DISPLAY 0.638298 (-1540 5050);
FORCEPROP 1 LAST PACK_TYPE 0201LF
J 2
(-1540 4950);
DISPLAY 0.638298 (-1540 4950);
FORCEPROP 2 LAST CDS_LIB pure_quanta
J 2
(-1500 5125);
DISPLAY INVISIBLE (-1500 5125);
FORCEPROP 1 LAST PATH I76
J 2
(-1550 5300);
DISPLAY 0.978723 (-1550 5300);
PAINT WHITE (-1550 5300);
DISPLAY INVISIBLE (-1550 5300);
FORCEPROP 1 LAST PART_NUMBER CS31001FE17
J 2
(-1540 5000);
DISPLAY 0.638298 (-1540 5000);
DISPLAY INVISIBLE (-1540 5000);
FORCEADD Q_RES..2
(-1325 5125);
FORCEPROP 1 LAST LOCATION R1061
J 0
(-1280 5250);
DISPLAY 0.638298 (-1280 5250);
FORCEPROP 0 LAST $SEC 1
J 0
(-1275 5300);
DISPLAY 0.680851 (-1275 5300);
PAINT MONO (-1275 5300);
DISPLAY INVISIBLE (-1275 5300);
FORCEPROP 0 LAST CDS_SEC 1
J 0
(-1275 5300);
DISPLAY 0.680851 (-1275 5300);
DISPLAY INVISIBLE (-1275 5300);
FORCEPROP 1 LASTPIN (-1325 5225) $PN 1
J 0
(-1320 5187);
DISPLAY 0.787234 (-1320 5187);
PAINT MONO (-1320 5187);
FORCEPROP 1 LASTPIN (-1325 5025) $PN 2
J 0
(-1320 5035);
DISPLAY 0.787234 (-1320 5035);
PAINT MONO (-1320 5035);
FORCEPROP 1 LAST MATERIAL CHIP
J 0
(-1285 5050);
DISPLAY 0.638298 (-1285 5050);
FORCEPROP 1 LAST TOLERANCE 1%
J 0
(-1280 5150);
DISPLAY 0.638298 (-1280 5150);
FORCEPROP 1 LAST PACK_TYPE 0201LF
J 0
(-1285 4950);
DISPLAY 0.638298 (-1285 4950);
FORCEPROP 1 LAST VALUE 10K
J 0
(-1280 5200);
DISPLAY 0.638298 (-1280 5200);
FORCEPROP 1 LAST WATTAGE 1/20W
J 0
(-1285 5100);
DISPLAY 0.638298 (-1285 5100);
FORCEPROP 2 LAST CDS_LIB pure_quanta
J 0
(-1325 5125);
DISPLAY INVISIBLE (-1325 5125);
FORCEPROP 1 LAST PATH I77
J 0
(-1275 5300);
DISPLAY 0.978723 (-1275 5300);
PAINT WHITE (-1275 5300);
DISPLAY INVISIBLE (-1275 5300);
FORCEPROP 1 LAST PART_NUMBER CS31001FE17
J 0
(-1285 5000);
DISPLAY 0.638298 (-1285 5000);
DISPLAY INVISIBLE (-1285 5000);
FORCEADD Q_RES..2
R 2
(-1500 5950);
FORCEPROP 1 LAST LOCATION R1065
J 2
(-1545 6075);
DISPLAY 0.787234 (-1545 6075);
FORCEPROP 0 LAST $SEC 1
J 0
(-1525 6125);
DISPLAY 0.680851 (-1525 6125);
PAINT MONO (-1525 6125);
DISPLAY INVISIBLE (-1525 6125);
FORCEPROP 0 LAST CDS_SEC 1
J 0
(-1525 6125);
DISPLAY 0.680851 (-1525 6125);
DISPLAY INVISIBLE (-1525 6125);
FORCEPROP 1 LASTPIN (-1500 6050) $PN 1
J 2
(-1505 6012);
DISPLAY 0.787234 (-1505 6012);
PAINT MONO (-1505 6012);
FORCEPROP 1 LASTPIN (-1500 5850) $PN 2
J 2
(-1505 5860);
DISPLAY 0.787234 (-1505 5860);
PAINT MONO (-1505 5860);
FORCEPROP 1 LAST TOLERANCE 5%
J 2
(-1545 5975);
DISPLAY 0.787234 (-1545 5975);
FORCEPROP 1 LAST VALUE 4.7K
J 2
(-1545 6025);
DISPLAY 0.787234 (-1545 6025);
FORCEPROP 1 LAST MATERIAL EMPTY
J 2
(-1540 5875);
DISPLAY 0.787234 (-1540 5875);
FORCEPROP 1 LAST WATTAGE 1/20W
J 2
(-1540 5925);
DISPLAY 0.787234 (-1540 5925);
FORCEPROP 1 LAST PACK_TYPE 0201LF
J 2
(-1550 5800);
DISPLAY 0.787234 (-1550 5800);
FORCEPROP 2 LAST CDS_LIB pure_quanta
J 2
(-1500 5950);
DISPLAY INVISIBLE (-1500 5950);
FORCEPROP 1 LAST PATH I78
J 2
(-1550 6125);
DISPLAY 0.978723 (-1550 6125);
PAINT WHITE (-1550 6125);
DISPLAY INVISIBLE (-1550 6125);
FORCEPROP 1 LAST PART_NUMBER CS24701JE04
J 2
(-1540 5825);
DISPLAY 0.978723 (-1540 5825);
DISPLAY INVISIBLE (-1540 5825);
FORCEADD OFFPAGE..1
R 2
(-550 5350);
FORCEPROP 2 LAST $XR1 299 
J 0
(-274 5350);
DISPLAY 0.638298 (-274 5350);
PAINT MONO (-274 5350);
FORCEPROP 2 LAST $XR0 81 
J 0
(-364 5350);
DISPLAY 0.638298 (-364 5350);
PAINT MONO (-364 5350);
FORCEPROP 2 LAST CDS_LIB standard
J 0
(-550 5350);
DISPLAY INVISIBLE (-550 5350);
FORCEPROP 1 LAST OFFPAGE TRUE
J 2
(-875 5225);
DISPLAY 0.872340 (-875 5225);
PAINT GREEN (-875 5225);
DISPLAY INVISIBLE (-875 5225);
FORCEPROP 1 LAST COMMENT_BODY TRUE
J 2
(-675 5250);
DISPLAY 0.872340 (-675 5250);
PAINT GREEN (-675 5250);
DISPLAY INVISIBLE (-675 5250);
FORCEPROP 2 LAST PATH I79
J 0
(-250 5400);
DISPLAY 0.680851 (-250 5400);
DISPLAY INVISIBLE (-250 5400);
FORCEADD Q_RES..2
(-8675 4950);
FORCEPROP 1 LAST LOCATION R1072
J 0
(-8630 5075);
DISPLAY 0.787234 (-8630 5075);
FORCEPROP 0 LAST $SEC 1
J 0
(-8625 5125);
DISPLAY 0.680851 (-8625 5125);
PAINT MONO (-8625 5125);
DISPLAY INVISIBLE (-8625 5125);
FORCEPROP 0 LAST CDS_SEC 1
J 0
(-8625 5125);
DISPLAY 0.680851 (-8625 5125);
DISPLAY INVISIBLE (-8625 5125);
FORCEPROP 1 LASTPIN (-8675 5050) $PN 1
J 0
(-8670 5012);
DISPLAY 0.787234 (-8670 5012);
PAINT MONO (-8670 5012);
FORCEPROP 1 LASTPIN (-8675 4850) $PN 2
J 0
(-8670 4860);
DISPLAY 0.787234 (-8670 4860);
PAINT MONO (-8670 4860);
FORCEPROP 1 LAST WATTAGE 1/20W
J 0
(-8635 4925);
DISPLAY 0.787234 (-8635 4925);
FORCEPROP 1 LAST PACK_TYPE 0201LF
J 0
(-8635 4775);
DISPLAY 0.787234 (-8635 4775);
FORCEPROP 1 LAST MATERIAL CHIP
J 0
(-8635 4875);
DISPLAY 0.787234 (-8635 4875);
FORCEPROP 1 LAST TOLERANCE 1%
J 0
(-8630 4975);
DISPLAY 0.787234 (-8630 4975);
FORCEPROP 1 LAST VALUE 10K
J 0
(-8630 5025);
DISPLAY 0.787234 (-8630 5025);
FORCEPROP 2 LAST CDS_LIB pure_quanta
J 0
(-8675 4950);
DISPLAY INVISIBLE (-8675 4950);
FORCEPROP 1 LAST PATH I8
J 0
(-8625 5125);
DISPLAY 0.978723 (-8625 5125);
PAINT WHITE (-8625 5125);
DISPLAY INVISIBLE (-8625 5125);
FORCEPROP 1 LAST PART_NUMBER CS31001FE17
J 0
(-8635 4825);
DISPLAY 0.510638 (-8635 4825);
DISPLAY INVISIBLE (-8635 4825);
FORCEADD OFFPAGE..1
R 2
(-525 5500);
FORCEPROP 2 LAST $XR1 299 
J 0
(-249 5500);
DISPLAY 0.638298 (-249 5500);
PAINT MONO (-249 5500);
FORCEPROP 2 LAST $XR0 81 
J 0
(-339 5500);
DISPLAY 0.638298 (-339 5500);
PAINT MONO (-339 5500);
FORCEPROP 2 LAST CDS_LIB standard
J 0
(-525 5500);
DISPLAY INVISIBLE (-525 5500);
FORCEPROP 1 LAST OFFPAGE TRUE
J 2
(-850 5375);
DISPLAY 0.872340 (-850 5375);
PAINT GREEN (-850 5375);
DISPLAY INVISIBLE (-850 5375);
FORCEPROP 1 LAST COMMENT_BODY TRUE
J 2
(-650 5400);
DISPLAY 0.872340 (-650 5400);
PAINT GREEN (-650 5400);
DISPLAY INVISIBLE (-650 5400);
FORCEPROP 2 LAST PATH I80
J 0
(-225 5550);
DISPLAY 0.680851 (-225 5550);
DISPLAY INVISIBLE (-225 5550);
FORCEADD P1V0..1
(-1500 6200);
FORCEPROP 3 LASTPIN (-1500 6150) SIG_NAME P1V8_CPU0_RT_1D\g
J 0
(-1490 6160);
DISPLAY 0.659574 (-1490 6160);
PAINT MONO (-1490 6160);
DISPLAY INVISIBLE (-1490 6160);
FORCEPROP 1 LAST HDL_POWER P1V8_CPU0_RT_1D
J 1
(-1500 6250);
DISPLAY 0.489362 (-1500 6250);
PAINT SKYBLUE (-1500 6250);
FORCEPROP 2 LAST CDS_LIB pure_quanta_power
J 0
(-1500 6200);
DISPLAY INVISIBLE (-1500 6200);
FORCEPROP 1 LAST PATH I81
J 0
(-1450 6225);
DISPLAY 0.872340 (-1450 6225);
PAINT AQUA (-1450 6225);
DISPLAY INVISIBLE (-1450 6225);
FORCEADD OFFPAGE..5
R 2
(-1950 5375);
FORCEPROP 2 LAST $XR0 299 
J 0
(-1761 5375);
DISPLAY 0.638298 (-1761 5375);
PAINT MONO (-1761 5375);
FORCEPROP 2 LAST CDS_LIB standard
J 0
(-1950 5375);
DISPLAY INVISIBLE (-1950 5375);
FORCEPROP 1 LAST OFFPAGE TRUE
J 2
(-2275 5250);
DISPLAY 0.872340 (-2275 5250);
PAINT GREEN (-2275 5250);
DISPLAY INVISIBLE (-2275 5250);
FORCEPROP 1 LAST COMMENT_BODY TRUE
J 2
(-2050 5300);
DISPLAY 0.872340 (-2050 5300);
PAINT GREEN (-2050 5300);
DISPLAY INVISIBLE (-2050 5300);
FORCEPROP 2 LAST PATH I82
J 0
(-1750 5425);
DISPLAY 0.680851 (-1750 5425);
DISPLAY INVISIBLE (-1750 5425);
FORCEADD PT5161LRS..3
(-4400 2250);
FORCEPROP 1 LAST LOCATION U6012
J 0
(-4900 3875);
DISPLAY 0.723404 (-4900 3875);
PAINT SKYBLUE (-4900 3875);
FORCEPROP 0 LAST $SEC 3
J 0
(-4900 4025);
DISPLAY 0.680851 (-4900 4025);
PAINT MONO (-4900 4025);
DISPLAY INVISIBLE (-4900 4025);
FORCEPROP 0 LAST CDS_SEC 3
J 0
(-4900 4025);
DISPLAY 0.680851 (-4900 4025);
DISPLAY INVISIBLE (-4900 4025);
FORCEPROP 0 LASTPIN (-3800 2200) $PN G35
J 0
(-3790 2210);
DISPLAY 0.680851 (-3790 2210);
PAINT MONO (-3790 2210);
FORCEPROP 0 LASTPIN (-5050 1550) $PN FF5
J 2
(-5060 1560);
DISPLAY 0.680851 (-5060 1560);
PAINT MONO (-5060 1560);
FORCEPROP 0 LASTPIN (-5050 1450) $PN FJ3
J 2
(-5060 1460);
DISPLAY 0.680851 (-5060 1460);
PAINT MONO (-5060 1460);
FORCEPROP 0 LASTPIN (-5050 3450) $PN FJ6
J 2
(-5060 3460);
DISPLAY 0.680851 (-5060 3460);
PAINT MONO (-5060 3460);
FORCEPROP 0 LASTPIN (-5050 3350) $PN FJ23
J 2
(-5060 3360);
DISPLAY 0.680851 (-5060 3360);
PAINT MONO (-5060 3360);
FORCEPROP 0 LASTPIN (-5050 3250) $PN FJ25
J 2
(-5060 3260);
DISPLAY 0.680851 (-5060 3260);
PAINT MONO (-5060 3260);
FORCEPROP 0 LASTPIN (-5050 3150) $PN FJ28
J 2
(-5060 3160);
DISPLAY 0.680851 (-5060 3160);
PAINT MONO (-5060 3160);
FORCEPROP 0 LASTPIN (-3800 1800) $PN FJ31
J 0
(-3790 1810);
DISPLAY 0.680851 (-3790 1810);
PAINT MONO (-3790 1810);
FORCEPROP 0 LASTPIN (-3800 3550) $PN B3
J 0
(-3790 3560);
DISPLAY 0.680851 (-3790 3560);
PAINT MONO (-3790 3560);
FORCEPROP 0 LASTPIN (-3800 3250) $PN B6
J 0
(-3790 3260);
DISPLAY 0.680851 (-3790 3260);
PAINT MONO (-3790 3260);
FORCEPROP 0 LASTPIN (-3800 3450) $PN B9
J 0
(-3790 3460);
DISPLAY 0.680851 (-3790 3460);
PAINT MONO (-3790 3460);
FORCEPROP 0 LASTPIN (-3800 3000) $PN FF8
J 0
(-3790 3010);
DISPLAY 0.680851 (-3790 3010);
PAINT MONO (-3790 3010);
FORCEPROP 0 LASTPIN (-3800 3350) $PN B12
J 0
(-3790 3360);
DISPLAY 0.680851 (-3790 3360);
PAINT MONO (-3790 3360);
FORCEPROP 0 LASTPIN (-3800 3150) $PN E8
J 0
(-3790 3160);
DISPLAY 0.680851 (-3790 3160);
PAINT MONO (-3790 3160);
FORCEPROP 0 LASTPIN (-3800 2700) $PN FJ9
J 0
(-3790 2710);
DISPLAY 0.680851 (-3790 2710);
PAINT MONO (-3790 2710);
FORCEPROP 0 LASTPIN (-3800 2100) $PN F2
J 0
(-3790 2110);
DISPLAY 0.680851 (-3790 2110);
PAINT MONO (-3790 2110);
FORCEPROP 0 LASTPIN (-3800 950) $PN E18
J 0
(-3790 960);
DISPLAY 0.680851 (-3790 960);
PAINT MONO (-3790 960);
FORCEPROP 0 LASTPIN (-3800 1100) $PN B16
J 0
(-3790 1110);
DISPLAY 0.680851 (-3790 1110);
PAINT MONO (-3790 1110);
FORCEPROP 0 LASTPIN (-5050 950) $PN FF18
J 2
(-5060 960);
DISPLAY 0.680851 (-5060 960);
PAINT MONO (-5060 960);
FORCEPROP 0 LASTPIN (-5050 1100) $PN FJ16
J 2
(-5060 1110);
DISPLAY 0.680851 (-5060 1110);
PAINT MONO (-5060 1110);
FORCEPROP 0 LASTPIN (-3800 2000) $PN FF11
J 0
(-3790 2010);
DISPLAY 0.680851 (-3790 2010);
PAINT MONO (-3790 2010);
FORCEPROP 0 LASTPIN (-3800 2600) $PN E11
J 0
(-3790 2610);
DISPLAY 0.680851 (-3790 2610);
PAINT MONO (-3790 2610);
FORCEPROP 0 LASTPIN (-3800 2500) $PN FF33
J 0
(-3790 2510);
DISPLAY 0.680851 (-3790 2510);
PAINT MONO (-3790 2510);
FORCEPROP 0 LASTPIN (-5050 2550) $PN F34
J 2
(-5060 2560);
DISPLAY 0.680851 (-5060 2560);
PAINT MONO (-5060 2560);
FORCEPROP 0 LASTPIN (-5050 2450) $PN B23
J 2
(-5060 2460);
DISPLAY 0.680851 (-5060 2460);
PAINT MONO (-5060 2460);
FORCEPROP 0 LASTPIN (-5050 2350) $PN B25
J 2
(-5060 2360);
DISPLAY 0.680851 (-5060 2360);
PAINT MONO (-5060 2360);
FORCEPROP 0 LASTPIN (-5050 2800) $PN B31
J 2
(-5060 2810);
DISPLAY 0.680851 (-5060 2810);
PAINT MONO (-5060 2810);
FORCEPROP 0 LASTPIN (-5050 2700) $PN B28
J 2
(-5060 2710);
DISPLAY 0.680851 (-5060 2710);
PAINT MONO (-5060 2710);
FORCEPROP 0 LASTPIN (-3800 1600) $PN E30
J 0
(-3790 1610);
DISPLAY 0.680851 (-3790 1610);
PAINT MONO (-3790 1610);
FORCEPROP 0 LASTPIN (-5050 2050) $PN FF24
J 2
(-5060 2060);
DISPLAY 0.680851 (-5060 2060);
PAINT MONO (-5060 2060);
FORCEPROP 0 LASTPIN (-5050 1950) $PN FF27
J 2
(-5060 1960);
DISPLAY 0.680851 (-5060 1960);
PAINT MONO (-5060 1960);
FORCEPROP 0 LASTPIN (-5050 1850) $PN FF30
J 2
(-5060 1860);
DISPLAY 0.680851 (-5060 1860);
PAINT MONO (-5060 1860);
FORCEPROP 1 LAST MATERIAL IC
J 0
(-4900 3725);
DISPLAY 0.723404 (-4900 3725);
PAINT GREEN (-4900 3725);
FORCEPROP 2 LAST PART_TYPE SMLF
J 0
(-4900 3975);
DISPLAY 0.680851 (-4900 3975);
FORCEPROP 2 LAST VALUE PT5161LRS
J 0
(-4900 3925);
DISPLAY 0.680851 (-4900 3925);
FORCEPROP 2 LAST CDS_LIB pure_quanta
J 0
(-4400 2250);
DISPLAY INVISIBLE (-4400 2250);
FORCEPROP 1 LAST CDS_LMAN_SYM_OUTLINE -500,1450,450,-1400
J 0
(-4400 2250);
DISPLAY 0.468085 (-4400 2250);
PAINT GREEN (-4400 2250);
DISPLAY INVISIBLE (-4400 2250);
FORCEPROP 1 LAST NEEDS_NO_SIZE TRUE
J 0
(-4400 2250);
DISPLAY 0.723404 (-4400 2250);
PAINT GREEN (-4400 2250);
DISPLAY INVISIBLE (-4400 2250);
FORCEPROP 1 LAST PATH I83
J 0
(-4400 2250);
DISPLAY 0.723404 (-4400 2250);
PAINT GREEN (-4400 2250);
DISPLAY INVISIBLE (-4400 2250);
FORCEPROP 1 LAST PART_NUMBER AJ051610U03
J 0
(-4900 3800);
DISPLAY 0.723404 (-4900 3800);
PAINT GREEN (-4900 3800);
DISPLAY INVISIBLE (-4900 3800);
FORCEADD Q_RES..1
(-2725 3150);
FORCEPROP 1 LAST LOCATION R1400
J 0
(-2850 3150);
DISPLAY 0.787234 (-2850 3150);
PAINT WHITE (-2850 3150);
FORCEPROP 0 LAST $SEC 1
J 0
(-2350 3200);
DISPLAY 0.680851 (-2350 3200);
PAINT MONO (-2350 3200);
DISPLAY INVISIBLE (-2350 3200);
FORCEPROP 0 LAST CDS_SEC 1
J 0
(-2350 3200);
DISPLAY 0.680851 (-2350 3200);
DISPLAY INVISIBLE (-2350 3200);
FORCEPROP 1 LASTPIN (-2825 3150) $PN 1
J 0
(-2813 3162);
DISPLAY 0.787234 (-2813 3162);
PAINT MONO (-2813 3162);
FORCEPROP 1 LASTPIN (-2625 3150) $PN 2
J 0
(-2663 3162);
DISPLAY 0.787234 (-2663 3162);
PAINT MONO (-2663 3162);
FORCEPROP 1 LAST PACK_TYPE 0201LF
J 0
(-2350 3150);
DISPLAY 0.638298 (-2350 3150);
FORCEPROP 1 LAST MATERIAL CHIP
J 0
(-2500 3150);
DISPLAY 0.638298 (-2500 3150);
FORCEPROP 1 LAST VALUE 1K
J 2
(-2525 3150);
DISPLAY 0.638298 (-2525 3150);
FORCEPROP 2 LAST CDS_LIB pure_quanta
J 0
(-2725 3150);
DISPLAY INVISIBLE (-2725 3150);
FORCEPROP 1 LAST WATTAGE 1/20W
J 2
(-2750 3000);
DISPLAY 0.638298 (-2750 3000);
DISPLAY INVISIBLE (-2750 3000);
FORCEPROP 1 LAST TOLERANCE 1%
J 0
(-2725 3050);
DISPLAY 0.638298 (-2725 3050);
DISPLAY INVISIBLE (-2725 3050);
FORCEPROP 1 LAST PATH I84
J 0
(-2775 3300);
DISPLAY 0.978723 (-2775 3300);
PAINT WHITE (-2775 3300);
DISPLAY INVISIBLE (-2775 3300);
FORCEPROP 1 LAST PART_NUMBER CS21001FE07
J 0
(-2775 3250);
DISPLAY 0.978723 (-2775 3250);
DISPLAY INVISIBLE (-2775 3250);
FORCEADD UNIVERSAL_GND..1
R 1
(-1975 3150);
FORCEPROP 3 LASTPIN (-2025 3150) SIG_NAME GND\g
J 0
(-2015 3160);
DISPLAY 0.659574 (-2015 3160);
PAINT MONO (-2015 3160);
DISPLAY INVISIBLE (-2015 3160);
FORCEPROP 2 LAST CDS_LIB pure_quanta_power
J 0
(-1975 3150);
DISPLAY INVISIBLE (-1975 3150);
FORCEPROP 1 LAST HDL_POWER GND
R 1
J 1
(-1900 3175);
DISPLAY 0.872340 (-1900 3175);
PAINT GREEN (-1900 3175);
DISPLAY INVISIBLE (-1900 3175);
FORCEPROP 1 LAST PATH I88
R 1
J 0
(-1975 3225);
DISPLAY 0.872340 (-1975 3225);
PAINT AQUA (-1975 3225);
DISPLAY INVISIBLE (-1975 3225);
FORCEADD Q_RES..2
(-8350 4950);
FORCEPROP 1 LAST LOCATION R1074
J 0
(-8305 5075);
DISPLAY 0.787234 (-8305 5075);
FORCEPROP 0 LAST $SEC 1
J 0
(-8300 5125);
DISPLAY 0.680851 (-8300 5125);
PAINT MONO (-8300 5125);
DISPLAY INVISIBLE (-8300 5125);
FORCEPROP 0 LAST CDS_SEC 1
J 0
(-8300 5125);
DISPLAY 0.680851 (-8300 5125);
DISPLAY INVISIBLE (-8300 5125);
FORCEPROP 1 LASTPIN (-8350 5050) $PN 1
J 0
(-8345 5012);
DISPLAY 0.787234 (-8345 5012);
PAINT MONO (-8345 5012);
FORCEPROP 1 LASTPIN (-8350 4850) $PN 2
J 0
(-8345 4860);
DISPLAY 0.787234 (-8345 4860);
PAINT MONO (-8345 4860);
FORCEPROP 1 LAST MATERIAL CHIP
J 0
(-8310 4875);
DISPLAY 0.787234 (-8310 4875);
FORCEPROP 1 LAST WATTAGE 1/20W
J 0
(-8310 4925);
DISPLAY 0.787234 (-8310 4925);
FORCEPROP 1 LAST VALUE 4.7K
J 0
(-8305 5025);
DISPLAY 0.787234 (-8305 5025);
FORCEPROP 1 LAST TOLERANCE 5%
J 0
(-8305 4975);
DISPLAY 0.787234 (-8305 4975);
FORCEPROP 1 LAST PACK_TYPE 0201LF
J 0
(-8310 4775);
DISPLAY 0.787234 (-8310 4775);
FORCEPROP 2 LAST CDS_LIB pure_quanta
J 0
(-8350 4950);
DISPLAY INVISIBLE (-8350 4950);
FORCEPROP 1 LAST PATH I9
J 0
(-8300 5125);
DISPLAY 0.978723 (-8300 5125);
PAINT WHITE (-8300 5125);
DISPLAY INVISIBLE (-8300 5125);
FORCEPROP 1 LAST PART_NUMBER CS24701JE04
J 0
(-8310 4825);
DISPLAY 0.978723 (-8310 4825);
DISPLAY INVISIBLE (-8310 4825);
FORCEADD GND..1
(-1375 2825);
FORCEPROP 3 LASTPIN (-1375 2875) SIG_NAME GND\g
J 0
(-1365 2885);
DISPLAY 0.659574 (-1365 2885);
PAINT MONO (-1365 2885);
DISPLAY INVISIBLE (-1365 2885);
FORCEPROP 2 LAST CDS_LIB pure_quanta_power
J 0
(-1375 2825);
DISPLAY INVISIBLE (-1375 2825);
FORCEPROP 1 LAST SIZE 1B
J 0
(-1300 2775);
DISPLAY 0.851064 (-1300 2775);
PAINT GREEN (-1300 2775);
DISPLAY INVISIBLE (-1300 2775);
FORCEPROP 2 LAST BOM_COST MEM
J 0
(-1475 2900);
DISPLAY 0.808511 (-1475 2900);
DISPLAY INVISIBLE (-1475 2900);
FORCEPROP 1 LAST HDL_POWER GND
J 0
(-1375 2975);
DISPLAY 0.851064 (-1375 2975);
PAINT GREEN (-1375 2975);
DISPLAY INVISIBLE (-1375 2975);
FORCEPROP 1 LAST PATH I94
J 0
(-1300 2825);
DISPLAY 0.872340 (-1300 2825);
PAINT AQUA (-1300 2825);
DISPLAY INVISIBLE (-1300 2825);
FORCEADD Q_RES..2
(-1375 3225);
FORCEPROP 1 LAST LOCATION R1406
J 0
(-1330 3350);
DISPLAY 0.787234 (-1330 3350);
PAINT WHITE (-1330 3350);
FORCEPROP 0 LAST $SEC 1
J 0
(-1325 3400);
DISPLAY 0.680851 (-1325 3400);
PAINT MONO (-1325 3400);
DISPLAY INVISIBLE (-1325 3400);
FORCEPROP 0 LAST CDS_SEC 1
J 0
(-1325 3400);
DISPLAY 0.680851 (-1325 3400);
DISPLAY INVISIBLE (-1325 3400);
FORCEPROP 1 LASTPIN (-1375 3325) $PN 1
J 0
(-1370 3287);
DISPLAY 0.787234 (-1370 3287);
PAINT MONO (-1370 3287);
FORCEPROP 1 LASTPIN (-1375 3125) $PN 2
J 0
(-1370 3135);
DISPLAY 0.787234 (-1370 3135);
PAINT MONO (-1370 3135);
FORCEPROP 1 LAST VALUE 10K
J 0
(-1330 3300);
DISPLAY 0.787234 (-1330 3300);
FORCEPROP 1 LAST WATTAGE 1/20W
J 0
(-1335 3200);
DISPLAY 0.787234 (-1335 3200);
FORCEPROP 1 LAST MATERIAL CHIP
J 0
(-1335 3150);
DISPLAY 0.787234 (-1335 3150);
FORCEPROP 1 LAST TOLERANCE 1%
J 0
(-1330 3250);
DISPLAY 0.787234 (-1330 3250);
FORCEPROP 1 LAST PACK_TYPE 0201LF
J 0
(-1335 3050);
DISPLAY 0.787234 (-1335 3050);
FORCEPROP 2 LAST CDS_LIB pure_quanta
J 0
(-1375 3225);
DISPLAY INVISIBLE (-1375 3225);
FORCEPROP 1 LAST PATH I95
J 0
(-1325 3400);
DISPLAY 0.978723 (-1325 3400);
PAINT WHITE (-1325 3400);
DISPLAY INVISIBLE (-1325 3400);
FORCEPROP 1 LAST PART_NUMBER CS31001FE17
J 0
(-1335 3100);
DISPLAY 0.510638 (-1335 3100);
DISPLAY INVISIBLE (-1335 3100);
FORCEADD Q_RES..2
(-1375 3750);
FORCEPROP 1 LAST LOCATION R1405
J 0
(-1330 3875);
DISPLAY 0.787234 (-1330 3875);
PAINT WHITE (-1330 3875);
FORCEPROP 0 LAST $SEC 1
J 0
(-1325 3925);
DISPLAY 0.680851 (-1325 3925);
PAINT MONO (-1325 3925);
DISPLAY INVISIBLE (-1325 3925);
FORCEPROP 0 LAST CDS_SEC 1
J 0
(-1325 3925);
DISPLAY 0.680851 (-1325 3925);
DISPLAY INVISIBLE (-1325 3925);
FORCEPROP 1 LASTPIN (-1375 3850) $PN 1
J 0
(-1370 3812);
DISPLAY 0.787234 (-1370 3812);
PAINT MONO (-1370 3812);
FORCEPROP 1 LASTPIN (-1375 3650) $PN 2
J 0
(-1370 3660);
DISPLAY 0.787234 (-1370 3660);
PAINT MONO (-1370 3660);
FORCEPROP 1 LAST PACK_TYPE 0201LF
J 0
(-1335 3575);
DISPLAY 0.787234 (-1335 3575);
FORCEPROP 1 LAST VALUE 1K
J 0
(-1330 3825);
DISPLAY 0.787234 (-1330 3825);
FORCEPROP 1 LAST MATERIAL EMPTY
J 0
(-1335 3675);
DISPLAY 0.787234 (-1335 3675);
PAINT RED (-1335 3675);
FORCEPROP 1 LAST WATTAGE 1/20W
J 0
(-1335 3725);
DISPLAY 0.787234 (-1335 3725);
FORCEPROP 1 LAST TOLERANCE 1%
J 0
(-1330 3775);
DISPLAY 0.787234 (-1330 3775);
FORCEPROP 2 LAST CDS_LIB pure_quanta
J 0
(-1375 3750);
DISPLAY INVISIBLE (-1375 3750);
FORCEPROP 1 LAST PATH I96
J 0
(-1325 3925);
DISPLAY 0.978723 (-1325 3925);
PAINT WHITE (-1325 3925);
DISPLAY INVISIBLE (-1325 3925);
FORCEPROP 1 LAST PART_NUMBER CS21001FE07
J 0
(-1335 3625);
DISPLAY 0.978723 (-1335 3625);
DISPLAY INVISIBLE (-1335 3625);
FORCEADD P1V0..1
(-1375 4150);
FORCEPROP 3 LASTPIN (-1375 4100) SIG_NAME P1V8_CPU0_RT_1D\g
J 0
(-1365 4110);
DISPLAY 0.659574 (-1365 4110);
PAINT MONO (-1365 4110);
DISPLAY INVISIBLE (-1365 4110);
FORCEPROP 1 LAST HDL_POWER P1V8_CPU0_RT_1D
J 1
(-1375 4200);
DISPLAY 0.489362 (-1375 4200);
PAINT SKYBLUE (-1375 4200);
FORCEPROP 2 LAST CDS_LIB pure_quanta_power
J 0
(-1375 4150);
DISPLAY INVISIBLE (-1375 4150);
FORCEPROP 1 LAST PATH I97
J 0
(-1325 4175);
DISPLAY 0.872340 (-1325 4175);
PAINT AQUA (-1325 4175);
DISPLAY INVISIBLE (-1325 4175);
FORCEADD OFFPAGE..1
R 2
(-525 3475);
FORCEPROP 2 LAST $XR0 299 
J 0
(-339 3475);
DISPLAY 0.638298 (-339 3475);
PAINT MONO (-339 3475);
FORCEPROP 2 LAST CDS_LIB standard
J 0
(-525 3475);
DISPLAY INVISIBLE (-525 3475);
FORCEPROP 1 LAST OFFPAGE TRUE
J 2
(-850 3350);
DISPLAY 0.872340 (-850 3350);
DISPLAY INVISIBLE (-850 3350);
FORCEPROP 1 LAST COMMENT_BODY TRUE
J 2
(-650 3375);
DISPLAY 0.872340 (-650 3375);
PAINT GREEN (-650 3375);
DISPLAY INVISIBLE (-650 3375);
FORCEPROP 2 LAST PATH I98
J 0
(-350 3550);
DISPLAY 0.680851 (-350 3550);
DISPLAY INVISIBLE (-350 3550);
FORCEADD Q_RES..1
(-2700 2200);
FORCEPROP 1 LAST LOCATION R1404
J 0
(-2750 2250);
DISPLAY 0.978723 (-2750 2250);
FORCEPROP 0 LAST $SEC 1
J 0
(-2750 2300);
DISPLAY 0.680851 (-2750 2300);
PAINT MONO (-2750 2300);
DISPLAY INVISIBLE (-2750 2300);
FORCEPROP 0 LAST CDS_SEC 1
J 0
(-2750 2300);
DISPLAY 0.680851 (-2750 2300);
DISPLAY INVISIBLE (-2750 2300);
FORCEPROP 1 LASTPIN (-2800 2200) $PN 1
J 0
(-2788 2212);
DISPLAY 0.787234 (-2788 2212);
PAINT MONO (-2788 2212);
FORCEPROP 1 LASTPIN (-2600 2200) $PN 2
J 0
(-2638 2212);
DISPLAY 0.787234 (-2638 2212);
PAINT MONO (-2638 2212);
FORCEPROP 1 LAST PACK_TYPE 0201LF
J 0
(-2275 2200);
DISPLAY 0.638298 (-2275 2200);
FORCEPROP 1 LAST VALUE 4.7K
J 2
(-2450 2200);
DISPLAY 0.638298 (-2450 2200);
FORCEPROP 1 LAST MATERIAL CHIP
J 0
(-2425 2200);
DISPLAY 0.638298 (-2425 2200);
FORCEPROP 1 LAST WATTAGE 1/20W
J 2
(-2725 2050);
DISPLAY 0.978723 (-2725 2050);
DISPLAY INVISIBLE (-2725 2050);
FORCEPROP 1 LAST TOLERANCE 5%
J 0
(-2700 2100);
DISPLAY 0.978723 (-2700 2100);
DISPLAY INVISIBLE (-2700 2100);
FORCEPROP 2 LAST CDS_LIB pure_quanta
J 0
(-2700 2200);
DISPLAY INVISIBLE (-2700 2200);
FORCEPROP 1 LAST PATH I99
J 0
(-2750 2350);
DISPLAY 0.978723 (-2750 2350);
PAINT WHITE (-2750 2350);
DISPLAY INVISIBLE (-2750 2350);
FORCEPROP 1 LAST PART_NUMBER CS24701JE04
J 0
(-2750 2300);
DISPLAY 0.978723 (-2750 2300);
DISPLAY INVISIBLE (-2750 2300);
FORCEADD DNS..1
(-1425 1350);
PAINT RED (-1425 1350);
FORCEPROP 2 LAST CDS_LIB mstr_misc
J 0
(-1425 1350);
DISPLAY INVISIBLE (-1425 1350);
FORCEPROP 1 LAST COMMENT_BODY TRUE
R 1
J 0
(-1350 1125);
DISPLAY 0.872340 (-1350 1125);
PAINT GREEN (-1350 1125);
DISPLAY INVISIBLE (-1350 1125);
FORCEADD DNS..1
(-1125 1300);
PAINT RED (-1125 1300);
FORCEPROP 2 LAST CDS_LIB mstr_misc
J 0
(-1125 1300);
DISPLAY INVISIBLE (-1125 1300);
FORCEPROP 1 LAST COMMENT_BODY TRUE
R 1
J 0
(-1050 1075);
DISPLAY 0.872340 (-1050 1075);
PAINT GREEN (-1050 1075);
DISPLAY INVISIBLE (-1050 1075);
FORCEADD DNS..1
(-825 1325);
PAINT RED (-825 1325);
FORCEPROP 2 LAST CDS_LIB mstr_misc
J 0
(-825 1325);
DISPLAY INVISIBLE (-825 1325);
FORCEPROP 1 LAST COMMENT_BODY TRUE
R 1
J 0
(-750 1100);
DISPLAY 0.872340 (-750 1100);
PAINT GREEN (-750 1100);
DISPLAY INVISIBLE (-750 1100);
FORCEADD DNS..1
(-550 1325);
PAINT RED (-550 1325);
FORCEPROP 2 LAST CDS_LIB mstr_misc
J 0
(-550 1325);
DISPLAY INVISIBLE (-550 1325);
FORCEPROP 1 LAST COMMENT_BODY TRUE
R 1
J 0
(-475 1100);
DISPLAY 0.872340 (-475 1100);
PAINT GREEN (-475 1100);
DISPLAY INVISIBLE (-475 1100);
FORCEADD DNS..1
(-1300 3750);
PAINT RED (-1300 3750);
FORCEPROP 2 LAST CDS_LIB mstr_misc
J 0
(-1300 3750);
DISPLAY INVISIBLE (-1300 3750);
FORCEPROP 1 LAST COMMENT_BODY TRUE
R 1
J 0
(-1225 3525);
DISPLAY 0.872340 (-1225 3525);
PAINT GREEN (-1225 3525);
DISPLAY INVISIBLE (-1225 3525);
FORCEADD QUANTA_TITLE_BLOCK_C..1
(0 0);
FORCEPROP 0 LAST CDS_CON_LAST_MODIFIED Thu Sep 14 16:12:57 2023
J 0
(-1885 15);
DISPLAY INVISIBLE (-1885 15);
FORCEPROP 1 LAST CUSTOM_TXT_CDS <CON_LAST_MODIFIED>
J 0
(-1885 15);
DISPLAY 0.978723 (-1885 15);
FORCEPROP 2 LAST CUSTOM_TXT_CDS <XR_PAGE_TITLE>
J 0
(-7890 5250);
DISPLAY 0.638298 (-7890 5250);
PAINT PINK (-7890 5250);
DISPLAY INVISIBLE (-7890 5250);
FORCEPROP 1 LAST CUSTOM_TXT_CDS <NAME_2>
J 0
(-3175 50);
FORCEPROP 1 LAST CUSTOM_TXT_CDS <NAME_1>
J 0
(-3175 175);
FORCEPROP 1 LAST CUSTOM_TXT_CDS <Q_NUMBER>
J 0
(-1403 103);
DISPLAY 1.212766 (-1403 103);
FORCEPROP 1 LAST CUSTOM_TXT_CDS <Q_PROJ>
J 0
(-2382 102);
DISPLAY 1.212766 (-2382 102);
FORCEPROP 1 LAST CUSTOM_TXT_CDS <Q_REV>
J 0
(-184 103);
DISPLAY 1.212766 (-184 103);
FORCEPROP 1 LAST CUSTOM_TXT_CDS <CON_PAGE_NUM> OF <CON_TOTAL_PAGES>
J 0
(-446 18);
DISPLAY 0.978723 (-446 18);
FORCEPROP 1 LAST Q_TITLE RETIMER_CPU0_P2(5)
J 0
(-9366 26);
DISPLAY 2.446809 (-9366 26);
PAINT GREEN (-9366 26);
FORCEPROP 2 LAST PAGE_BORDER TRUE
J 0
(-7890 5250);
DISPLAY 0.638298 (-7890 5250);
PAINT PINK (-7890 5250);
DISPLAY INVISIBLE (-7890 5250);
FORCEPROP 1 LAST CDS_LMAN_SYM_OUTLINE -9475,6775,100,-125
J 0
(0 0);
DISPLAY 0.468085 (0 0);
PAINT GREEN (0 0);
DISPLAY INVISIBLE (0 0);
FORCEPROP 2 LAST CDS_LIB pure_quanta
J 0
(0 0);
DISPLAY INVISIBLE (0 0);
FORCEPROP 2 LAST CDS_XR_PAGE_TITLE CR-299 : @T6G_MB_LIB.T6G(SCH_1):PAGE299
J 0
(-7890 5250);
DISPLAY 0.638298 (-7890 5250);
PAINT PINK (-7890 5250);
DISPLAY INVISIBLE (-7890 5250);
FORCEPROP 1 LAST Q_DEPT BU9
J 1
(-3763 49);
DISPLAY 1.957447 (-3763 49);
PAINT GREEN (-3763 49);
DISPLAY INVISIBLE (-3763 49);
FORCEPROP 1 LAST COMMENT_BODY TRUE
J 0
(12 -13);
DISPLAY 0.978723 (12 -13);
PAINT GREEN (12 -13);
DISPLAY INVISIBLE (12 -13);
FORCEADD DNS..1
(-1500 5975);
PAINT RED (-1500 5975);
FORCEPROP 2 LAST CDS_LIB mstr_misc
J 0
(-1500 5975);
DISPLAY INVISIBLE (-1500 5975);
FORCEPROP 1 LAST COMMENT_BODY TRUE
R 1
J 0
(-1425 5750);
DISPLAY 0.872340 (-1425 5750);
PAINT GREEN (-1425 5750);
DISPLAY INVISIBLE (-1425 5750);
FORCEADD DNS..1
(-2800 5900);
PAINT RED (-2800 5900);
FORCEPROP 2 LAST CDS_LIB mstr_misc
J 0
(-2800 5900);
DISPLAY INVISIBLE (-2800 5900);
FORCEPROP 1 LAST COMMENT_BODY TRUE
R 1
J 0
(-2725 5675);
DISPLAY 0.872340 (-2725 5675);
PAINT GREEN (-2725 5675);
DISPLAY INVISIBLE (-2725 5675);
FORCEADD DNS..1
(-3150 5925);
PAINT RED (-3150 5925);
FORCEPROP 2 LAST CDS_LIB mstr_misc
J 0
(-3150 5925);
DISPLAY INVISIBLE (-3150 5925);
FORCEPROP 1 LAST COMMENT_BODY TRUE
R 1
J 0
(-3075 5700);
DISPLAY 0.872340 (-3075 5700);
PAINT GREEN (-3075 5700);
DISPLAY INVISIBLE (-3075 5700);
FORCEADD DNS..1
(-3450 5100);
PAINT RED (-3450 5100);
FORCEPROP 2 LAST CDS_LIB mstr_misc
J 0
(-3450 5100);
DISPLAY INVISIBLE (-3450 5100);
FORCEPROP 1 LAST COMMENT_BODY TRUE
R 1
J 0
(-3375 4875);
DISPLAY 0.872340 (-3375 4875);
PAINT GREEN (-3375 4875);
DISPLAY INVISIBLE (-3375 4875);
FORCEADD DNS..1
(-4975 5400);
PAINT RED (-4975 5400);
FORCEPROP 2 LAST CDS_LIB mstr_misc
J 0
(-4975 5400);
DISPLAY INVISIBLE (-4975 5400);
FORCEPROP 1 LAST COMMENT_BODY TRUE
R 1
J 0
(-4900 5175);
DISPLAY 0.872340 (-4900 5175);
PAINT GREEN (-4900 5175);
DISPLAY INVISIBLE (-4900 5175);
FORCEADD DNS..1
(-7350 5875);
PAINT RED (-7350 5875);
FORCEPROP 2 LAST CDS_LIB mstr_misc
J 0
(-7350 5875);
DISPLAY INVISIBLE (-7350 5875);
FORCEPROP 1 LAST COMMENT_BODY TRUE
R 1
J 0
(-7275 5650);
DISPLAY 0.872340 (-7275 5650);
PAINT GREEN (-7275 5650);
DISPLAY INVISIBLE (-7275 5650);
FORCEADD DNS..1
(-7675 5925);
PAINT RED (-7675 5925);
FORCEPROP 2 LAST CDS_LIB mstr_misc
J 0
(-7675 5925);
DISPLAY INVISIBLE (-7675 5925);
FORCEPROP 1 LAST COMMENT_BODY TRUE
R 1
J 0
(-7600 5700);
DISPLAY 0.872340 (-7600 5700);
PAINT GREEN (-7600 5700);
DISPLAY INVISIBLE (-7600 5700);
FORCEADD DNS..1
(-7950 5875);
PAINT RED (-7950 5875);
FORCEPROP 2 LAST CDS_LIB mstr_misc
J 0
(-7950 5875);
DISPLAY INVISIBLE (-7950 5875);
FORCEPROP 1 LAST COMMENT_BODY TRUE
R 1
J 0
(-7875 5650);
DISPLAY 0.872340 (-7875 5650);
PAINT GREEN (-7875 5650);
DISPLAY INVISIBLE (-7875 5650);
FORCEADD DNS..1
(-6075 575);
PAINT RED (-6075 575);
FORCEPROP 2 LAST CDS_LIB mstr_misc
J 0
(-6075 575);
DISPLAY INVISIBLE (-6075 575);
FORCEPROP 1 LAST COMMENT_BODY TRUE
R 1
J 0
(-6000 350);
DISPLAY 0.872340 (-6000 350);
PAINT GREEN (-6000 350);
DISPLAY INVISIBLE (-6000 350);
FORCEADD DNS..1
(-6450 525);
PAINT RED (-6450 525);
FORCEPROP 2 LAST CDS_LIB mstr_misc
J 0
(-6450 525);
DISPLAY INVISIBLE (-6450 525);
FORCEPROP 1 LAST COMMENT_BODY TRUE
R 1
J 0
(-6375 300);
DISPLAY 0.872340 (-6375 300);
PAINT GREEN (-6375 300);
DISPLAY INVISIBLE (-6375 300);
FORCEADD DNS..1
(-8250 5900);
PAINT RED (-8250 5900);
FORCEPROP 2 LAST CDS_LIB mstr_misc
J 0
(-8250 5900);
DISPLAY INVISIBLE (-8250 5900);
FORCEPROP 1 LAST COMMENT_BODY TRUE
R 1
J 0
(-8175 5675);
DISPLAY 0.872340 (-8175 5675);
PAINT GREEN (-8175 5675);
DISPLAY INVISIBLE (-8175 5675);
FORCEADD DNS..1
(-8850 5875);
PAINT RED (-8850 5875);
FORCEPROP 2 LAST CDS_LIB mstr_misc
J 0
(-8850 5875);
DISPLAY INVISIBLE (-8850 5875);
FORCEPROP 1 LAST COMMENT_BODY TRUE
R 1
J 0
(-8775 5650);
DISPLAY 0.872340 (-8775 5650);
PAINT GREEN (-8775 5650);
DISPLAY INVISIBLE (-8775 5650);
FORCEADD DNS..1
(-8950 4000);
PAINT RED (-8950 4000);
FORCEPROP 2 LAST CDS_LIB mstr_misc
J 0
(-8950 4000);
DISPLAY INVISIBLE (-8950 4000);
FORCEPROP 1 LAST COMMENT_BODY TRUE
R 1
J 0
(-8875 3775);
DISPLAY 0.872340 (-8875 3775);
PAINT GREEN (-8875 3775);
DISPLAY INVISIBLE (-8875 3775);
WIRE 16 -1 (-2600 2200)(-2025 2200);
WIRE 16 -1 (-625 575)(-625 425);
WIRE 16 -1 (-6325 525)(-6325 350);
WIRE 16 -1 (-6175 525)(-6175 350);
WIRE 16 -1 (-9000 3250)(-9000 3125);
WIRE 16 -1 (-5050 5350)(-5050 5150);
WIRE 16 -1 (-5050 6075)(-5050 6250);
WIRE 16 -1 (-3800 1600)(-3125 1600);
WIRE 16 -1 (-9000 4125)(-9000 4300);
WIRE 16 -1 (-1500 5025)(-1500 4800);
WIRE 16 -1 (-1325 5025)(-1325 4825);
WIRE 16 -1 (-1500 6150)(-1500 6050);
WIRE 16 -1 (-2625 3150)(-2025 3150);
WIRE 16 -1 (-1375 3125)(-1375 2875);
WIRE 16 -1 (-1375 3850)(-1375 4100);
WIRE 16 -1 (-6450 1450)(-7850 1450);
FORCEPROP 2 LAST SIG_NAME SMB_RT_CPU0_P2_ROM_MUX_1D_SDA
J 0
(-7785 1460);
DISPLAY 0.680851 (-7785 1460);
PAINT SKYBLUE (-7785 1460);
WIRE 16 -1 (-5050 1450)(-6250 1450);
FORCEPROP 2 LAST SIG_NAME SMB_RT_CPU0_P2_ROM_MUX_1D_R_SDA
J 0
(-6185 1475);
DISPLAY 0.680851 (-6185 1475);
PAINT SKYBLUE (-6185 1475);
FORCEPROP 2 LASTPROP $XRERR UNIQUE?
J 0
(-6425 1475);
DISPLAY 0.638298 (-6425 1475);
PAINT MONO (-6425 1475);
DISPLAY INVISIBLE (-6425 1475);
WIRE 16 -1 (-6450 1550)(-7900 1550);
FORCEPROP 2 LAST SIG_NAME SMB_RT_CPU0_P2_ROM_MUX_1D_SCL
J 0
(-7810 1560);
DISPLAY 0.680851 (-7810 1560);
PAINT SKYBLUE (-7810 1560);
WIRE 16 -1 (-5050 1550)(-6250 1550);
FORCEPROP 2 LAST SIG_NAME SMB_RT_CPU0_P2_ROM_MUX_1D_R_SCL
J 0
(-6185 1575);
DISPLAY 0.680851 (-6185 1575);
PAINT SKYBLUE (-6185 1575);
FORCEPROP 2 LASTPROP $XRERR UNIQUE?
J 0
(-6425 1575);
DISPLAY 0.638298 (-6425 1575);
PAINT MONO (-6425 1575);
DISPLAY INVISIBLE (-6425 1575);
WIRE 16 -1 (-7875 3800)(-9000 3800);
FORCEPROP 2 LAST SIG_NAME RT_CPU0_P2_SCAN_MODE
J 0
(-8610 3810);
DISPLAY 0.680851 (-8610 3810);
PAINT SKYBLUE (-8610 3810);
WIRE 16 -1 (-9000 3925)(-9000 3800);
WIRE 16 -1 (-9000 3800)(-9000 3450);
WIRE 16 -1 (-625 1225)(-625 1050);
WIRE 16 -1 (-625 1050)(-625 775);
WIRE 16 -1 (-2550 1050)(-625 1050);
FORCEPROP 2 LAST SIG_NAME JTAG_TCK_RT_CPU0_P2
J 0
(-2385 1060);
DISPLAY 0.680851 (-2385 1060);
PAINT WHITE (-2385 1060);
WIRE 16 -1 (-1175 1200)(-1175 950);
WIRE 16 -1 (-2550 950)(-1175 950);
FORCEPROP 2 LAST SIG_NAME JTAG_TMS_RT_CPU0_P2
J 0
(-2360 960);
DISPLAY 0.680851 (-2360 960);
PAINT WHITE (-2360 960);
WIRE 16 -1 (-1450 1200)(-1450 900);
WIRE 16 -1 (-2550 900)(-1450 900);
FORCEPROP 2 LAST SIG_NAME JTAG_TDI_RT_CPU0_P2
J 0
(-2385 910);
DISPLAY 0.680851 (-2385 910);
PAINT WHITE (-2385 910);
WIRE 16 -1 (-3800 2000)(-2700 2000);
FORCEPROP 2 LAST SIG_NAME RST_RT_CPU0_P2_RESET_N
J 0
(-3610 2010);
DISPLAY 0.680851 (-3610 2010);
PAINT SKYBLUE (-3610 2010);
FORCEPROP 2 LASTPROP $XRERR UNIQUE?
J 0
(-3850 2010);
DISPLAY 0.638298 (-3850 2010);
PAINT MONO (-3850 2010);
DISPLAY INVISIBLE (-3850 2010);
WIRE 16 -1 (-3800 2100)(-2700 2100);
FORCEPROP 2 LAST SIG_NAME RST_RT_CPU0_P2_PERST_N
J 0
(-3635 2110);
DISPLAY 0.680851 (-3635 2110);
PAINT SKYBLUE (-3635 2110);
FORCEPROP 2 LASTPROP $XRERR UNIQUE?
J 0
(-3875 2110);
DISPLAY 0.638298 (-3875 2110);
PAINT MONO (-3875 2110);
DISPLAY INVISIBLE (-3875 2110);
WIRE 16 -1 (-900 1200)(-900 1000);
WIRE 16 -1 (-2550 1000)(-900 1000);
FORCEPROP 2 LAST SIG_NAME JTAG_TDO_RT_CPU0_P2
J 0
(-2360 1010);
DISPLAY 0.680851 (-2360 1010);
PAINT WHITE (-2360 1010);
WIRE 16 -1 (-900 1400)(-900 1550);
WIRE 16 -1 (-900 1550)(-625 1550);
WIRE 16 -1 (-1175 1550)(-900 1550);
WIRE 16 -1 (-1450 1550)(-1175 1550);
WIRE 16 -1 (-1175 1400)(-1175 1550);
WIRE 16 -1 (-625 1425)(-625 1550);
WIRE 16 -1 (-625 1550)(-625 1575);
WIRE 16 -1 (-1450 1400)(-1450 1550);
WIRE 16 -1 (-3800 2200)(-2800 2200);
FORCEPROP 2 LAST SIG_NAME CLKREQ_RT_CPU0_P2_N
J 0
(-3535 2210);
DISPLAY 0.680851 (-3535 2210);
PAINT WHITE (-3535 2210);
FORCEPROP 2 LASTPROP $XRERR UNIQUE?
J 0
(-3775 2210);
DISPLAY 0.638298 (-3775 2210);
PAINT MONO (-3775 2210);
DISPLAY INVISIBLE (-3775 2210);
WIRE 16 -1 (-3800 2500)(-2450 2500);
FORCEPROP 2 LAST SIG_NAME RT_CPU0_P2_SCAN_MODE
J 0
(-3510 2510);
DISPLAY 0.680851 (-3510 2510);
PAINT SKYBLUE (-3510 2510);
WIRE 16 -1 (-3800 2600)(-2475 2600);
FORCEPROP 2 LAST SIG_NAME RXDET_BYP_RT_CPU0_P2
J 0
(-3485 2610);
DISPLAY 0.680851 (-3485 2610);
PAINT WHITE (-3485 2610);
WIRE 16 -1 (-3800 2700)(-2475 2700);
FORCEPROP 2 LAST SIG_NAME MODE_RT_CPU0_P2
J 0
(-3485 2710);
DISPLAY 0.680851 (-3485 2710);
PAINT SKYBLUE (-3485 2710);
WIRE 16 -1 (-3800 3450)(-2800 3450);
FORCEPROP 2 LAST SIG_NAME JTAG_TDO_RT_CPU0_P2
J 0
(-3610 3460);
DISPLAY 0.680851 (-3610 3460);
PAINT WHITE (-3610 3460);
WIRE 16 -1 (-3800 3550)(-2800 3550);
FORCEPROP 2 LAST SIG_NAME JTAG_TCK_RT_CPU0_P2
J 0
(-3635 3560);
DISPLAY 0.680851 (-3635 3560);
PAINT WHITE (-3635 3560);
WIRE 16 -1 (-2500 2100)(-1125 2100);
FORCEPROP 2 LAST SIG_NAME RST_RT_CPU0_P2_PERST_R_N
J 0
(-1960 2110);
DISPLAY 0.680851 (-1960 2110);
PAINT SKYBLUE (-1960 2110);
WIRE 16 -1 (-3200 6225)(-2850 6225);
WIRE 16 -1 (-3500 6225)(-3200 6225);
WIRE 16 -1 (-3200 6225)(-3200 6000);
WIRE 16 -1 (-2850 6225)(-2850 5975);
WIRE 16 -1 (-3500 6000)(-3500 6225);
WIRE 16 -1 (-3500 6225)(-3500 6275);
WIRE 16 -1 (-2850 5025)(-2850 4850);
WIRE 16 -1 (-2850 4850)(-3200 4850);
WIRE 16 -1 (-3200 5025)(-3200 4850);
WIRE 16 -1 (-3200 4850)(-3500 4850);
WIRE 16 -1 (-3500 5025)(-3500 4850);
WIRE 16 -1 (-3500 4850)(-3500 4750);
WIRE 16 -1 (-8975 4850)(-8975 4625);
WIRE 16 -1 (-8975 4625)(-8675 4625);
WIRE 16 -1 (-8675 4625)(-8350 4625);
WIRE 16 -1 (-8675 4850)(-8675 4625);
WIRE 16 -1 (-8050 4625)(-8350 4625);
WIRE 16 -1 (-8350 4850)(-8350 4625);
WIRE 16 -1 (-7750 4625)(-8050 4625);
WIRE 16 -1 (-8050 4825)(-8050 4625);
WIRE 16 -1 (-7750 4625)(-7450 4625);
WIRE 16 -1 (-7750 4825)(-7750 4625);
WIRE 16 -1 (-7450 4800)(-7450 4625);
WIRE 16 -1 (-7450 4625)(-7450 4500);
WIRE 16 -1 (-7750 6200)(-7450 6200);
WIRE 16 -1 (-7750 6200)(-8050 6200);
WIRE 16 -1 (-7750 6200)(-7750 5975);
WIRE 16 -1 (-7450 6200)(-7450 6000);
WIRE 16 -1 (-8050 6200)(-8050 5950);
WIRE 16 -1 (-8050 6200)(-8350 6200);
WIRE 16 -1 (-8975 6200)(-8350 6200);
WIRE 16 -1 (-8350 6200)(-8350 6000);
WIRE 16 -1 (-8975 6250)(-8975 6200);
WIRE 16 -1 (-8975 6200)(-8975 6000);
WIRE 16 -1 (-1375 3325)(-1375 3475);
WIRE 16 -1 (-575 3475)(-1375 3475);
FORCEPROP 2 LAST SIG_NAME RXDET_BYP_RT_CPU0_P2
J 0
(-1260 3485);
DISPLAY 0.680851 (-1260 3485);
PAINT WHITE (-1260 3485);
WIRE 16 -1 (-1375 3475)(-1375 3650);
WIRE 16 -1 (-5050 3250)(-6000 3250);
FORCEPROP 2 LAST SIG_NAME GPIO2_RT_CPU0_P2
J 0
(-5860 3260);
DISPLAY 0.680851 (-5860 3260);
PAINT SKYBLUE (-5860 3260);
WIRE 16 -1 (-1500 5225)(-1500 5500);
WIRE 16 -1 (-575 5500)(-1500 5500);
FORCEPROP 2 LAST SIG_NAME RST_RT_CPU0_P2_RESET_R_N
J 0
(-1460 5535);
DISPLAY 0.680851 (-1460 5535);
PAINT SKYBLUE (-1460 5535);
WIRE 16 -1 (-1500 5850)(-1500 5500);
WIRE 16 -1 (-1325 5350)(-600 5350);
WIRE 16 -1 (-1325 5225)(-1325 5350);
FORCEPROP 2 LAST SIG_NAME RST_RT_CPU0_P2_PERST_R_N
J 0
(-1360 5385);
DISPLAY 0.680851 (-1360 5385);
PAINT SKYBLUE (-1360 5385);
WIRE 16 -1 (-2000 5575)(-3500 5575);
FORCEPROP 2 LAST SIG_NAME RT_CPU0_P2_ADDR3
J 0
(-2785 5610);
DISPLAY 0.680851 (-2785 5610);
PAINT SKYBLUE (-2785 5610);
WIRE 16 -1 (-3500 5800)(-3500 5575);
WIRE 16 -1 (-3500 5575)(-3500 5225);
WIRE 16 -1 (-5050 5550)(-5050 5700);
WIRE 16 -1 (-4225 5700)(-5050 5700);
FORCEPROP 2 LAST SIG_NAME MODE_RT_CPU0_P2
J 0
(-4835 5710);
DISPLAY 0.680851 (-4835 5710);
PAINT SKYBLUE (-4835 5710);
WIRE 16 -1 (-5050 5875)(-5050 5700);
WIRE 16 -1 (-7750 5025)(-7750 5375);
WIRE 16 -1 (-6450 5375)(-7750 5375);
FORCEPROP 2 LAST SIG_NAME TEST2_RT_CPU0_P2
J 0
(-7010 5385);
DISPLAY 0.680851 (-7010 5385);
PAINT SKYBLUE (-7010 5385);
WIRE 16 -1 (-7750 5775)(-7750 5375);
WIRE 16 -1 (-8050 5025)(-8050 5425);
WIRE 16 -1 (-6450 5425)(-8050 5425);
FORCEPROP 2 LAST SIG_NAME TEST1_RT_CPU0_P2
J 0
(-7010 5435);
DISPLAY 0.680851 (-7010 5435);
PAINT SKYBLUE (-7010 5435);
WIRE 16 -1 (-8050 5750)(-8050 5425);
WIRE 16 -1 (-8975 5050)(-8975 5600);
WIRE 16 -1 (-6450 5600)(-8975 5600);
FORCEPROP 2 LAST SIG_NAME GPIO2_RT_CPU0_P2
J 0
(-7010 5610);
DISPLAY 0.680851 (-7010 5610);
PAINT SKYBLUE (-7010 5610);
WIRE 16 -1 (-8975 5800)(-8975 5600);
WIRE 16 -1 (-6450 5300)(-7450 5300);
FORCEPROP 2 LAST SIG_NAME JTAG_TEST_MODE_RT_CPU0_P2
J 0
(-7260 5310);
DISPLAY 0.680851 (-7260 5310);
PAINT SKYBLUE (-7260 5310);
WIRE 16 -1 (-7450 5800)(-7450 5300);
WIRE 16 -1 (-7450 5300)(-7450 5000);
WIRE 16 -1 (-6475 2800)(-7625 2800);
FORCEPROP 2 LAST SIG_NAME SMB_RT_CPU0_P2_R_SCL
J 0
(-7460 2810);
DISPLAY 0.680851 (-7460 2810);
PAINT SKYBLUE (-7460 2810);
WIRE 16 -1 (-5050 3150)(-6000 3150);
FORCEPROP 2 LAST SIG_NAME GPIO3_RT_CPU0_P2
J 0
(-5860 3160);
DISPLAY 0.680851 (-5860 3160);
PAINT SKYBLUE (-5860 3160);
WIRE 16 -1 (-8350 5050)(-8350 5475);
WIRE 16 -1 (-6450 5475)(-8350 5475);
FORCEPROP 2 LAST SIG_NAME TEST0_RT_CPU0_P2
J 0
(-7010 5485);
DISPLAY 0.680851 (-7010 5485);
PAINT SKYBLUE (-7010 5485);
WIRE 16 -1 (-8350 5800)(-8350 5475);
WIRE 16 -1 (-6450 5525)(-8675 5525);
FORCEPROP 2 LAST SIG_NAME GPIO3_RT_CPU0_P2
J 0
(-7035 5535);
DISPLAY 0.680851 (-7035 5535);
PAINT SKYBLUE (-7035 5535);
WIRE 16 -1 (-8675 5525)(-8675 5050);
WIRE 16 -1 (-6475 2700)(-7625 2700);
FORCEPROP 2 LAST SIG_NAME SMB_RT_CPU0_P2_R_SDA
J 0
(-7460 2710);
DISPLAY 0.680851 (-7460 2710);
PAINT SKYBLUE (-7460 2710);
WIRE 16 -1 (-5050 2700)(-6275 2700);
FORCEPROP 2 LAST SIG_NAME SMB_RT_CPU0_P2_R2_SDA
J 0
(-6035 2710);
DISPLAY 0.680851 (-6035 2710);
PAINT SKYBLUE (-6035 2710);
FORCEPROP 2 LASTPROP $XRERR UNIQUE?
J 0
(-6275 2710);
DISPLAY 0.638298 (-6275 2710);
PAINT MONO (-6275 2710);
DISPLAY INVISIBLE (-6275 2710);
WIRE 16 -1 (-5050 2800)(-6275 2800);
FORCEPROP 2 LAST SIG_NAME SMB_RT_CPU0_P2_R2_SCL
J 0
(-6035 2810);
DISPLAY 0.680851 (-6035 2810);
PAINT SKYBLUE (-6035 2810);
FORCEPROP 2 LASTPROP $XRERR UNIQUE?
J 0
(-6275 2810);
DISPLAY 0.638298 (-6275 2810);
PAINT MONO (-6275 2810);
DISPLAY INVISIBLE (-6275 2810);
WIRE 16 -1 (-5050 2550)(-5950 2550);
FORCEPROP 2 LAST SIG_NAME RT_CPU0_P2_ADDR1
J 0
(-5810 2560);
DISPLAY 0.680851 (-5810 2560);
PAINT SKYBLUE (-5810 2560);
WIRE 16 -1 (-5050 2450)(-5950 2450);
FORCEPROP 2 LAST SIG_NAME RT_CPU0_P2_ADDR2
J 0
(-5810 2460);
DISPLAY 0.680851 (-5810 2460);
PAINT SKYBLUE (-5810 2460);
WIRE 16 -1 (-5050 2350)(-5950 2350);
FORCEPROP 2 LAST SIG_NAME RT_CPU0_P2_ADDR3
J 0
(-5810 2360);
DISPLAY 0.680851 (-5810 2360);
PAINT SKYBLUE (-5810 2360);
WIRE 16 -1 (-5050 2050)(-6125 2050);
FORCEPROP 2 LAST SIG_NAME TEST0_RT_CPU0_P2
J 0
(-5810 2060);
DISPLAY 0.680851 (-5810 2060);
PAINT SKYBLUE (-5810 2060);
WIRE 16 -1 (-3200 5225)(-3200 5475);
WIRE 16 -1 (-2000 5475)(-3200 5475);
FORCEPROP 2 LAST SIG_NAME RT_CPU0_P2_ADDR2
J 0
(-2785 5485);
DISPLAY 0.680851 (-2785 5485);
PAINT SKYBLUE (-2785 5485);
WIRE 16 -1 (-3200 5475)(-3200 5800);
WIRE 16 -1 (-2850 5225)(-2850 5375);
WIRE 16 -1 (-2000 5375)(-2850 5375);
FORCEPROP 2 LAST SIG_NAME RT_CPU0_P2_ADDR1
J 0
(-2785 5385);
DISPLAY 0.680851 (-2785 5385);
PAINT SKYBLUE (-2785 5385);
WIRE 16 -1 (-2850 5375)(-2850 5775);
WIRE 16 -1 (-5050 1950)(-6125 1950);
FORCEPROP 2 LAST SIG_NAME TEST1_RT_CPU0_P2
J 0
(-5810 1960);
DISPLAY 0.680851 (-5810 1960);
PAINT SKYBLUE (-5810 1960);
WIRE 16 -1 (-5050 1100)(-6175 1100);
FORCEPROP 2 LAST SIG_NAME CLK_100M_RETIMER_CPU0_P2_DP
J 0
(-6085 1110);
DISPLAY 0.680851 (-6085 1110);
PAINT SKYBLUE (-6085 1110);
FORCEPROP 2 LASTPROP $XRERR UNIQUE?
J 0
(-6325 1110);
DISPLAY 0.638298 (-6325 1110);
PAINT MONO (-6325 1110);
DISPLAY INVISIBLE (-6325 1110);
WIRE 16 -1 (-6175 1100)(-6525 1100);
WIRE 16 -1 (-6175 1100)(-6175 725);
WIRE 16 -1 (-5050 1850)(-6125 1850);
FORCEPROP 2 LAST SIG_NAME TEST2_RT_CPU0_P2
J 0
(-5810 1860);
DISPLAY 0.680851 (-5810 1860);
PAINT SKYBLUE (-5810 1860);
WIRE 16 -1 (-6725 1100)(-8025 1100);
FORCEPROP 2 LAST SIG_NAME CLK_100M_RETIMER_CPU0_P2_R_DP
J 0
(-7960 1110);
DISPLAY 0.680851 (-7960 1110);
PAINT SKYBLUE (-7960 1110);
WIRE 16 -1 (-6725 950)(-8025 950);
FORCEPROP 2 LAST SIG_NAME CLK_100M_RETIMER_CPU0_P2_R_DN
J 0
(-7985 960);
DISPLAY 0.680851 (-7985 960);
PAINT SKYBLUE (-7985 960);
WIRE 16 -1 (-5050 950)(-6325 950);
FORCEPROP 2 LAST SIG_NAME CLK_100M_RETIMER_CPU0_P2_DN
J 0
(-6085 960);
DISPLAY 0.680851 (-6085 960);
PAINT SKYBLUE (-6085 960);
FORCEPROP 2 LASTPROP $XRERR UNIQUE?
J 0
(-6325 960);
DISPLAY 0.638298 (-6325 960);
PAINT MONO (-6325 960);
DISPLAY INVISIBLE (-6325 960);
WIRE 16 -1 (-6325 950)(-6325 725);
WIRE 16 -1 (-6325 950)(-6525 950);
WIRE 16 -1 (-2500 2000)(-1125 2000);
FORCEPROP 2 LAST SIG_NAME RST_RT_CPU0_P2_RESET_R_N
J 0
(-1985 2010);
DISPLAY 0.680851 (-1985 2010);
PAINT SKYBLUE (-1985 2010);
WIRE 16 -1 (-3800 3150)(-2825 3150);
FORCEPROP 2 LAST SIG_NAME JTAG_TRST_RT_CPU0_P2_N
J 0
(-3635 3160);
DISPLAY 0.680851 (-3635 3160);
PAINT WHITE (-3635 3160);
FORCEPROP 2 LASTPROP $XRERR UNIQUE?
J 0
(-3875 3160);
DISPLAY 0.638298 (-3875 3160);
PAINT MONO (-3875 3160);
DISPLAY INVISIBLE (-3875 3160);
WIRE 16 -1 (-3800 3250)(-2800 3250);
FORCEPROP 2 LAST SIG_NAME JTAG_TDI_RT_CPU0_P2
J 0
(-3635 3260);
DISPLAY 0.680851 (-3635 3260);
PAINT WHITE (-3635 3260);
WIRE 16 -1 (-3800 3350)(-2800 3350);
FORCEPROP 2 LAST SIG_NAME JTAG_TMS_RT_CPU0_P2
J 0
(-3610 3360);
DISPLAY 0.680851 (-3610 3360);
PAINT WHITE (-3610 3360);
WIRE 16 -1 (-3800 3000)(-2550 3000);
FORCEPROP 2 LAST SIG_NAME JTAG_TEST_MODE_RT_CPU0_P2
J 0
(-3610 3010);
DISPLAY 0.680851 (-3610 3010);
PAINT SKYBLUE (-3610 3010);
DOT 1 (-9000 3800);
DOT 1 (-1375 3475);
DOT 1 (-3500 6225);
DOT 1 (-2850 5375);
DOT 1 (-3500 5575);
DOT 1 (-3200 5475);
DOT 1 (-3200 4850);
DOT 1 (-3500 4850);
DOT 1 (-5050 5700);
DOT 1 (-7750 6200);
DOT 1 (-8050 6200);
DOT 1 (-7450 5300);
DOT 1 (-7750 5375);
DOT 1 (-8050 5425);
DOT 1 (-7450 4625);
DOT 1 (-7750 4625);
DOT 1 (-8050 4625);
DOT 1 (-6325 950);
DOT 1 (-8350 6200);
DOT 1 (-8975 6200);
DOT 1 (-8350 5475);
DOT 1 (-8975 5600);
DOT 1 (-8350 4625);
DOT 1 (-8675 4625);
DOT 1 (-6175 1100);
DOT 1 (-1500 5500);
DOT 1 (-3200 6225);
DOT 1 (-1175 1550);
DOT 1 (-625 1050);
DOT 1 (-900 1550);
DOT 1 (-625 1550);
FORCENOTE
CPU1 P0 RT ADDR: 0X48 (8-BIT) / 0X24 (7-BIT)
(-4300 4525) 0;
DISPLAY LEFT (-4300 4525);
DISPLAY 1.595745 (-4300 4525);
QUIT
